G04 ================== begin FILE IDENTIFICATION RECORD ==================*
G04 Layout Name:  D:/<user>/Wistron_project/16316-1/gbr-0621/16316-1.brd*
G04 Film Name:    TMASK*
G04 File Format:  Gerber RS274X*
G04 File Origin:  Cadence Allegro 16.5-S056*
G04 Origin Date:  Wed Jun 21 09:31:45 2017*
G04 *
G04 Layer:  VIA CLASS/SOLDERMASK_TOP*
G04 Layer:  PIN/SOLDERMASK_TOP*
G04 Layer:  PACKAGE GEOMETRY/SOLDERMASK_TOP*
G04 Layer:  DRAWING FORMAT/LAYER_PCB_STORY*
G04 Layer:  DRAWING FORMAT/LAYER_SOLDER_T*
G04 Layer:  BOARD GEOMETRY/SOLDERMASK_TOP*
G04 *
G04 Offset:    (0.00 0.00)*
G04 Mirror:    No*
G04 Mode:      Positive*
G04 Rotation:  0*
G04 FullContactRelief:  No*
G04 UndefLineWidth:     6.00*
G04 ================== end FILE IDENTIFICATION RECORD ====================*
%FSLAX35Y35*MOIN*%
%IR0*IPPOS*OFA0.00000B0.00000*MIA0B0*SFA1.00000B1.00000*%
%AMMACRO78*
4,1,40,.013,.017,
-.013,.017,
-.013695,.016939,
-.014368,.016759,
-.015,.016464,
-.015571,.016064,
-.016064,.015571,
-.016464,.015,
-.016759,.014368,
-.016939,.013695,
-.017,.013,
-.017,-.013,
-.016939,-.013695,
-.016759,-.014368,
-.016464,-.015,
-.016064,-.015571,
-.015571,-.016064,
-.015,-.016464,
-.014368,-.016759,
-.013695,-.016939,
-.013,-.017,
.013,-.017,
.013695,-.016939,
.014368,-.016759,
.015,-.016464,
.015571,-.016064,
.016064,-.015571,
.016464,-.015,
.016759,-.014368,
.016939,-.013695,
.017,-.013,
.017,.013,
.016939,.013695,
.016759,.014368,
.016464,.015,
.016064,.015571,
.015571,.016064,
.015,.016464,
.014368,.016759,
.013695,.016939,
.013,.017,
0.0*
%
%ADD78MACRO78*%
%AMMACRO37*
4,1,40,.017,-.013,
.017,.013,
.016939,.013695,
.016759,.014368,
.016464,.015,
.016064,.015571,
.015571,.016064,
.015,.016464,
.014368,.016759,
.013695,.016939,
.013,.017,
-.013,.017,
-.013695,.016939,
-.014368,.016759,
-.015,.016464,
-.015571,.016064,
-.016064,.015571,
-.016464,.015,
-.016759,.014368,
-.016939,.013695,
-.017,.013,
-.017,-.013,
-.016939,-.013695,
-.016759,-.014368,
-.016464,-.015,
-.016064,-.015571,
-.015571,-.016064,
-.015,-.016464,
-.014368,-.016759,
-.013695,-.016939,
-.013,-.017,
.013,-.017,
.013695,-.016939,
.014368,-.016759,
.015,-.016464,
.015571,-.016064,
.016064,-.015571,
.016464,-.015,
.016759,-.014368,
.016939,-.013695,
.017,-.013,
0.0*
%
%ADD37MACRO37*%
%ADD113R,.143X.011*%
%ADD11C,.02*%
%ADD87C,.03*%
%ADD76R,.122X.093*%
%ADD43C,.022*%
%AMMACRO98*
4,1,40,-.007,.004,
-.007,-.004,
-.00697,-.004347,
-.006879,-.004684,
-.006732,-.005,
-.006532,-.005286,
-.006286,-.005532,
-.006,-.005732,
-.005684,-.005879,
-.005347,-.00597,
-.005,-.006,
.005,-.006,
.005347,-.00597,
.005684,-.005879,
.006,-.005732,
.006286,-.005532,
.006532,-.005286,
.006732,-.005,
.006879,-.004684,
.00697,-.004347,
.007,-.004,
.007,.004,
.00697,.004347,
.006879,.004684,
.006732,.005,
.006532,.005286,
.006286,.005532,
.006,.005732,
.005684,.005879,
.005347,.00597,
.005,.006,
-.005,.006,
-.005347,.00597,
-.005684,.005879,
-.006,.005732,
-.006286,.005532,
-.006532,.005286,
-.006732,.005,
-.006879,.004684,
-.00697,.004347,
-.007,.004,
0.0*
%
%ADD98MACRO98*%
%ADD82C,.014*%
%ADD74R,.06X.008*%
%ADD101R,.008X.06*%
%ADD60C,.042*%
%ADD31C,.024*%
%ADD108C,.016*%
%ADD61R,.039X.108*%
%ADD30C,.026*%
%ADD12C,.08*%
%ADD105R,.039X.118*%
%ADD93C,.018*%
%ADD62O,.048X.166*%
%ADD91C,.028*%
%ADD94C,.029*%
%ADD63C,.048*%
%ADD55C,.094*%
%ADD110R,.098X.128*%
%ADD10C,.086*%
%AMMACRO104*
4,1,40,.008,-.014,
-.008,-.014,
-.008695,-.013939,
-.009368,-.013759,
-.01,-.013464,
-.010571,-.013064,
-.011064,-.012571,
-.011464,-.012,
-.011759,-.011368,
-.011939,-.010695,
-.012,-.01,
-.012,.01,
-.011939,.010695,
-.011759,.011368,
-.011464,.012,
-.011064,.012571,
-.010571,.013064,
-.01,.013464,
-.009368,.013759,
-.008695,.013939,
-.008,.014,
.008,.014,
.008695,.013939,
.009368,.013759,
.01,.013464,
.010571,.013064,
.011064,.012571,
.011464,.012,
.011759,.011368,
.011939,.010695,
.012,.01,
.012,-.01,
.011939,-.010695,
.011759,-.011368,
.011464,-.012,
.011064,-.012571,
.010571,-.013064,
.01,-.013464,
.009368,-.013759,
.008695,-.013939,
.008,-.014,
0.0*
%
%ADD104MACRO104*%
%ADD92C,.087*%
%ADD53C,.078*%
%AMMACRO45*
4,1,40,.0225,-.007,
.022378,-.008389,
.022018,-.009736,
.021428,-.011,
.020628,-.012142,
.019642,-.013128,
.0185,-.013928,
.017236,-.014518,
.015889,-.014878,
.0145,-.015,
-.0145,-.015,
-.015889,-.014878,
-.017236,-.014518,
-.0185,-.013928,
-.019642,-.013128,
-.020628,-.012142,
-.021428,-.011,
-.022018,-.009736,
-.022378,-.008389,
-.0225,-.007,
-.0225,.007,
-.022378,.008389,
-.022018,.009736,
-.021428,.011,
-.020628,.012142,
-.019642,.013128,
-.0185,.013928,
-.017236,.014518,
-.015889,.014878,
-.0145,.015,
.0145,.015,
.015889,.014878,
.017236,.014518,
.0185,.013928,
.019642,.013128,
.020628,.012142,
.021428,.011,
.022018,.009736,
.022378,.008389,
.0225,.007,
.0225,-.007,
0.0*
%
%ADD45MACRO45*%
%AMMACRO111*
4,1,40,-.007,-.0225,
-.008389,-.022378,
-.009736,-.022018,
-.011,-.021428,
-.012142,-.020628,
-.013128,-.019642,
-.013928,-.0185,
-.014518,-.017236,
-.014878,-.015889,
-.015,-.0145,
-.015,.0145,
-.014878,.015889,
-.014518,.017236,
-.013928,.0185,
-.013128,.019642,
-.012142,.020628,
-.011,.021428,
-.009736,.022018,
-.008389,.022378,
-.007,.0225,
.007,.0225,
.008389,.022378,
.009736,.022018,
.011,.021428,
.012142,.020628,
.013128,.019642,
.013928,.0185,
.014518,.017236,
.014878,.015889,
.015,.0145,
.015,-.0145,
.014878,-.015889,
.014518,-.017236,
.013928,-.0185,
.013128,-.019642,
.012142,-.020628,
.011,-.021428,
.009736,-.022018,
.008389,-.022378,
.007,-.0225,
-.007,-.0225,
0.0*
%
%ADD111MACRO111*%
%ADD56C,.097*%
%ADD71R,.065X.065*%
%ADD54C,.099*%
%AMMACRO21*
4,1,40,.011,-.007,
.011,.007,
.010939,.007695,
.010759,.008368,
.010464,.009,
.010064,.009571,
.009571,.010064,
.009,.010464,
.008368,.010759,
.007695,.010939,
.007,.011,
-.007,.011,
-.007695,.010939,
-.008368,.010759,
-.009,.010464,
-.009571,.010064,
-.010064,.009571,
-.010464,.009,
-.010759,.008368,
-.010939,.007695,
-.011,.007,
-.011,-.007,
-.010939,-.007695,
-.010759,-.008368,
-.010464,-.009,
-.010064,-.009571,
-.009571,-.010064,
-.009,-.010464,
-.008368,-.010759,
-.007695,-.010939,
-.007,-.011,
.007,-.011,
.007695,-.010939,
.008368,-.010759,
.009,-.010464,
.009571,-.010064,
.010064,-.009571,
.010464,-.009,
.010759,-.008368,
.010939,-.007695,
.011,-.007,
0.0*
%
%ADD21MACRO21*%
%AMMACRO13*
4,1,40,.007,.011,
-.007,.011,
-.007695,.010939,
-.008368,.010759,
-.009,.010464,
-.009571,.010064,
-.010064,.009571,
-.010464,.009,
-.010759,.008368,
-.010939,.007695,
-.011,.007,
-.011,-.007,
-.010939,-.007695,
-.010759,-.008368,
-.010464,-.009,
-.010064,-.009571,
-.009571,-.010064,
-.009,-.010464,
-.008368,-.010759,
-.007695,-.010939,
-.007,-.011,
.007,-.011,
.007695,-.010939,
.008368,-.010759,
.009,-.010464,
.009571,-.010064,
.010064,-.009571,
.010464,-.009,
.010759,-.008368,
.010939,-.007695,
.011,-.007,
.011,.007,
.010939,.007695,
.010759,.008368,
.010464,.009,
.010064,.009571,
.009571,.010064,
.009,.010464,
.008368,.010759,
.007695,.010939,
.007,.011,
0.0*
%
%ADD13MACRO13*%
%AMMACRO47*
4,1,40,-.012,.008,
-.012,-.008,
-.011939,-.008695,
-.011759,-.009368,
-.011464,-.01,
-.011064,-.010571,
-.010571,-.011064,
-.01,-.011464,
-.009368,-.011759,
-.008695,-.011939,
-.008,-.012,
.008,-.012,
.008695,-.011939,
.009368,-.011759,
.01,-.011464,
.010571,-.011064,
.011064,-.010571,
.011464,-.01,
.011759,-.009368,
.011939,-.008695,
.012,-.008,
.012,.008,
.011939,.008695,
.011759,.009368,
.011464,.01,
.011064,.010571,
.010571,.011064,
.01,.011464,
.009368,.011759,
.008695,.011939,
.008,.012,
-.008,.012,
-.008695,.011939,
-.009368,.011759,
-.01,.011464,
-.010571,.011064,
-.011064,.010571,
-.011464,.01,
-.011759,.009368,
-.011939,.008695,
-.012,.008,
0.0*
%
%ADD47MACRO47*%
%AMMACRO20*
4,1,40,.008,.012,
-.008,.012,
-.008695,.011939,
-.009368,.011759,
-.01,.011464,
-.010571,.011064,
-.011064,.010571,
-.011464,.01,
-.011759,.009368,
-.011939,.008695,
-.012,.008,
-.012,-.008,
-.011939,-.008695,
-.011759,-.009368,
-.011464,-.01,
-.011064,-.010571,
-.010571,-.011064,
-.01,-.011464,
-.009368,-.011759,
-.008695,-.011939,
-.008,-.012,
.008,-.012,
.008695,-.011939,
.009368,-.011759,
.01,-.011464,
.010571,-.011064,
.011064,-.010571,
.011464,-.01,
.011759,-.009368,
.011939,-.008695,
.012,-.008,
.012,.008,
.011939,.008695,
.011759,.009368,
.011464,.01,
.011064,.010571,
.010571,.011064,
.01,.011464,
.009368,.011759,
.008695,.011939,
.008,.012,
0.0*
%
%ADD20MACRO20*%
%AMMACRO57*
4,1,40,-.013,-.017,
.013,-.017,
.013695,-.016939,
.014368,-.016759,
.015,-.016464,
.015571,-.016064,
.016064,-.015571,
.016464,-.015,
.016759,-.014368,
.016939,-.013695,
.017,-.013,
.017,.013,
.016939,.013695,
.016759,.014368,
.016464,.015,
.016064,.015571,
.015571,.016064,
.015,.016464,
.014368,.016759,
.013695,.016939,
.013,.017,
-.013,.017,
-.013695,.016939,
-.014368,.016759,
-.015,.016464,
-.015571,.016064,
-.016064,.015571,
-.016464,.015,
-.016759,.014368,
-.016939,.013695,
-.017,.013,
-.017,-.013,
-.016939,-.013695,
-.016759,-.014368,
-.016464,-.015,
-.016064,-.015571,
-.015571,-.016064,
-.015,-.016464,
-.014368,-.016759,
-.013695,-.016939,
-.013,-.017,
0.0*
%
%ADD57MACRO57*%
%AMMACRO68*
4,1,6,-.025,-.0135,
-.005,.0065,
-.005,.0135,
.005,.0135,
.005,.0065,
.025,-.0135,
-.025,-.0135,
0.0*
%
%ADD68MACRO68*%
%AMMACRO34*
4,1,40,-.017,.013,
-.017,-.013,
-.016939,-.013695,
-.016759,-.014368,
-.016464,-.015,
-.016064,-.015571,
-.015571,-.016064,
-.015,-.016464,
-.014368,-.016759,
-.013695,-.016939,
-.013,-.017,
.013,-.017,
.013695,-.016939,
.014368,-.016759,
.015,-.016464,
.015571,-.016064,
.016064,-.015571,
.016464,-.015,
.016759,-.014368,
.016939,-.013695,
.017,-.013,
.017,.013,
.016939,.013695,
.016759,.014368,
.016464,.015,
.016064,.015571,
.015571,.016064,
.015,.016464,
.014368,.016759,
.013695,.016939,
.013,.017,
-.013,.017,
-.013695,.016939,
-.014368,.016759,
-.015,.016464,
-.015571,.016064,
-.016064,.015571,
-.016464,.015,
-.016759,.014368,
-.016939,.013695,
-.017,.013,
0.0*
%
%ADD34MACRO34*%
%AMMACRO84*
4,1,6,-.0135,.005,
-.0065,.005,
.0135,.025,
.0135,-.025,
-.0065,-.005,
-.0135,-.005,
-.0135,.005,
0.0*
%
%ADD84MACRO84*%
%AMMACRO22*
4,1,40,.011,-.007,
.011,.007,
.010939,.007695,
.010759,.008368,
.010464,.009,
.010064,.009571,
.009571,.010064,
.009,.010464,
.008368,.010759,
.007695,.010939,
.007,.011,
-.007,.011,
-.007695,.010939,
-.008368,.010759,
-.009,.010464,
-.009571,.010064,
-.010064,.009571,
-.010464,.009,
-.010759,.008368,
-.010939,.007695,
-.011,.007,
-.011,-.007,
-.010939,-.007695,
-.010759,-.008368,
-.010464,-.009,
-.010064,-.009571,
-.009571,-.010064,
-.009,-.010464,
-.008368,-.010759,
-.007695,-.010939,
-.007,-.011,
.007,-.011,
.007695,-.010939,
.008368,-.010759,
.009,-.010464,
.009571,-.010064,
.010064,-.009571,
.010464,-.009,
.010759,-.008368,
.010939,-.007695,
.011,-.007,
0.0*
%
%ADD22MACRO22*%
%AMMACRO14*
4,1,40,.007,.011,
-.007,.011,
-.007695,.010939,
-.008368,.010759,
-.009,.010464,
-.009571,.010064,
-.010064,.009571,
-.010464,.009,
-.010759,.008368,
-.010939,.007695,
-.011,.007,
-.011,-.007,
-.010939,-.007695,
-.010759,-.008368,
-.010464,-.009,
-.010064,-.009571,
-.009571,-.010064,
-.009,-.010464,
-.008368,-.010759,
-.007695,-.010939,
-.007,-.011,
.007,-.011,
.007695,-.010939,
.008368,-.010759,
.009,-.010464,
.009571,-.010064,
.010064,-.009571,
.010464,-.009,
.010759,-.008368,
.010939,-.007695,
.011,-.007,
.011,.007,
.010939,.007695,
.010759,.008368,
.010464,.009,
.010064,.009571,
.009571,.010064,
.009,.010464,
.008368,.010759,
.007695,.010939,
.007,.011,
0.0*
%
%ADD14MACRO14*%
%AMMACRO106*
4,1,20,.0635,-.1075,
.049,-.1075,
.049,-.118,
.0395,-.118,
.0395,-.1075,
-.0395,-.1075,
-.0395,-.118,
-.049,-.118,
-.049,-.1075,
-.0635,-.1075,
-.0635,.1075,
-.049,.1075,
-.049,.118,
-.0395,.118,
-.0395,.1075,
.0395,.1075,
.0395,.118,
.049,.118,
.049,.1075,
.0635,.1075,
.0635,-.1075,
0.0*
%
%ADD106MACRO106*%
%AMMACRO79*
4,1,20,-.1075,-.0635,
-.1075,-.049,
-.118,-.049,
-.118,-.0395,
-.1075,-.0395,
-.1075,.0395,
-.118,.0395,
-.118,.049,
-.1075,.049,
-.1075,.0635,
.1075,.0635,
.1075,.049,
.118,.049,
.118,.0395,
.1075,.0395,
.1075,-.0395,
.118,-.0395,
.118,-.049,
.1075,-.049,
.1075,-.0635,
-.1075,-.0635,
0.0*
%
%ADD79MACRO79*%
%AMMACRO44*
4,1,40,-.012,.008,
-.012,-.008,
-.011939,-.008695,
-.011759,-.009368,
-.011464,-.01,
-.011064,-.010571,
-.010571,-.011064,
-.01,-.011464,
-.009368,-.011759,
-.008695,-.011939,
-.008,-.012,
.008,-.012,
.008695,-.011939,
.009368,-.011759,
.01,-.011464,
.010571,-.011064,
.011064,-.010571,
.011464,-.01,
.011759,-.009368,
.011939,-.008695,
.012,-.008,
.012,.008,
.011939,.008695,
.011759,.009368,
.011464,.01,
.011064,.010571,
.010571,.011064,
.01,.011464,
.009368,.011759,
.008695,.011939,
.008,.012,
-.008,.012,
-.008695,.011939,
-.009368,.011759,
-.01,.011464,
-.010571,.011064,
-.011064,.010571,
-.011464,.01,
-.011759,.009368,
-.011939,.008695,
-.012,.008,
0.0*
%
%ADD44MACRO44*%
%AMMACRO19*
4,1,40,.008,.012,
-.008,.012,
-.008695,.011939,
-.009368,.011759,
-.01,.011464,
-.010571,.011064,
-.011064,.010571,
-.011464,.01,
-.011759,.009368,
-.011939,.008695,
-.012,.008,
-.012,-.008,
-.011939,-.008695,
-.011759,-.009368,
-.011464,-.01,
-.011064,-.010571,
-.010571,-.011064,
-.01,-.011464,
-.009368,-.011759,
-.008695,-.011939,
-.008,-.012,
.008,-.012,
.008695,-.011939,
.009368,-.011759,
.01,-.011464,
.010571,-.011064,
.011064,-.010571,
.011464,-.01,
.011759,-.009368,
.011939,-.008695,
.012,-.008,
.012,.008,
.011939,.008695,
.011759,.009368,
.011464,.01,
.011064,.010571,
.010571,.011064,
.01,.011464,
.009368,.011759,
.008695,.011939,
.008,.012,
0.0*
%
%ADD19MACRO19*%
%AMMACRO58*
4,1,40,-.013,-.017,
.013,-.017,
.013695,-.016939,
.014368,-.016759,
.015,-.016464,
.015571,-.016064,
.016064,-.015571,
.016464,-.015,
.016759,-.014368,
.016939,-.013695,
.017,-.013,
.017,.013,
.016939,.013695,
.016759,.014368,
.016464,.015,
.016064,.015571,
.015571,.016064,
.015,.016464,
.014368,.016759,
.013695,.016939,
.013,.017,
-.013,.017,
-.013695,.016939,
-.014368,.016759,
-.015,.016464,
-.015571,.016064,
-.016064,.015571,
-.016464,.015,
-.016759,.014368,
-.016939,.013695,
-.017,.013,
-.017,-.013,
-.016939,-.013695,
-.016759,-.014368,
-.016464,-.015,
-.016064,-.015571,
-.015571,-.016064,
-.015,-.016464,
-.014368,-.016759,
-.013695,-.016939,
-.013,-.017,
0.0*
%
%ADD58MACRO58*%
%AMMACRO35*
4,1,40,-.017,.013,
-.017,-.013,
-.016939,-.013695,
-.016759,-.014368,
-.016464,-.015,
-.016064,-.015571,
-.015571,-.016064,
-.015,-.016464,
-.014368,-.016759,
-.013695,-.016939,
-.013,-.017,
.013,-.017,
.013695,-.016939,
.014368,-.016759,
.015,-.016464,
.015571,-.016064,
.016064,-.015571,
.016464,-.015,
.016759,-.014368,
.016939,-.013695,
.017,-.013,
.017,.013,
.016939,.013695,
.016759,.014368,
.016464,.015,
.016064,.015571,
.015571,.016064,
.015,.016464,
.014368,.016759,
.013695,.016939,
.013,.017,
-.013,.017,
-.013695,.016939,
-.014368,.016759,
-.015,.016464,
-.015571,.016064,
-.016064,.015571,
-.016464,.015,
-.016759,.014368,
-.016939,.013695,
-.017,.013,
0.0*
%
%ADD35MACRO35*%
%ADD115R,.011X.03*%
%ADD114R,.03X.011*%
%ADD66R,.126X.201*%
%AMMACRO96*
4,1,42,-.00768,.00246,
-.00602,-.00537,
-.005913,-.005702,
-.005755,-.006013,
-.005545,-.006291,
-.00529,-.006529,
-.004997,-.006719,
-.004676,-.006855,
-.004336,-.006933,
-.003988,-.006951,
-.003642,-.006908,
-.00364,-.00691,
.00614,-.00483,
.006473,-.004727,
.006784,-.004568,
.007062,-.004358,
.007299,-.004103,
.007489,-.003811,
.007625,-.00349,
.007703,-.00315,
.007721,-.002802,
.00768,-.00246,
.00602,.00537,
.005913,.005702,
.005755,.006013,
.005545,.006291,
.00529,.006529,
.004997,.006719,
.004676,.006855,
.004336,.006933,
.003988,.006951,
.003642,.006908,
.00364,.00691,
-.00614,.00483,
-.006473,.004727,
-.006784,.004568,
-.007062,.004358,
-.007299,.004103,
-.007489,.003811,
-.007625,.00349,
-.007703,.00315,
-.007721,.002802,
-.00768,.00246,
0.0*
%
%ADD96MACRO96*%
%ADD103R,.06X.012*%
%ADD100R,.022X.04*%
%ADD41R,.042X.012*%
%ADD39R,.012X.042*%
%ADD121R,.06X.014*%
%ADD107R,.044X.012*%
%ADD118R,.014X.042*%
%ADD117R,.042X.014*%
%ADD99R,.105X.128*%
%ADD80R,.012X.044*%
%ADD48R,.014X.06*%
%ADD40R,.036X.012*%
%ADD38R,.012X.036*%
%ADD28R,.045X.03*%
%ADD81R,.128X.105*%
%ADD70R,.012X.036*%
%ADD69R,.036X.012*%
%ADD112R,.093X.011*%
%AMMACRO97*
4,1,40,.007,-.004,
.007,.004,
.00697,.004347,
.006879,.004684,
.006732,.005,
.006532,.005286,
.006286,.005532,
.006,.005732,
.005684,.005879,
.005347,.00597,
.005,.006,
-.005,.006,
-.005347,.00597,
-.005684,.005879,
-.006,.005732,
-.006286,.005532,
-.006532,.005286,
-.006732,.005,
-.006879,.004684,
-.00697,.004347,
-.007,.004,
-.007,-.004,
-.00697,-.004347,
-.006879,-.004684,
-.006732,-.005,
-.006532,-.005286,
-.006286,-.005532,
-.006,-.005732,
-.005684,-.005879,
-.005347,-.00597,
-.005,-.006,
.005,-.006,
.005347,-.00597,
.005684,-.005879,
.006,-.005732,
.006286,-.005532,
.006532,-.005286,
.006732,-.005,
.006879,-.004684,
.00697,-.004347,
.007,-.004,
0.0*
%
%ADD97MACRO97*%
%AMMACRO95*
4,1,40,-.004,-.007,
.004,-.007,
.004347,-.00697,
.004684,-.006879,
.005,-.006732,
.005286,-.006532,
.005532,-.006286,
.005732,-.006,
.005879,-.005684,
.00597,-.005347,
.006,-.005,
.006,.005,
.00597,.005347,
.005879,.005684,
.005732,.006,
.005532,.006286,
.005286,.006532,
.005,.006732,
.004684,.006879,
.004347,.00697,
.004,.007,
-.004,.007,
-.004347,.00697,
-.004684,.006879,
-.005,.006732,
-.005286,.006532,
-.005532,.006286,
-.005732,.006,
-.005879,.005684,
-.00597,.005347,
-.006,.005,
-.006,-.005,
-.00597,-.005347,
-.005879,-.005684,
-.005732,-.006,
-.005532,-.006286,
-.005286,-.006532,
-.005,-.006732,
-.004684,-.006879,
-.004347,-.00697,
-.004,-.007,
0.0*
%
%ADD95MACRO95*%
%ADD23R,.03X.064*%
%ADD109R,.05X.065*%
%ADD65R,.054X.025*%
%ADD83R,.065X.05*%
%ADD102R,.029X.043*%
%ADD46R,.065X.025*%
%ADD29R,.045X.09*%
%ADD89R,.043X.029*%
%ADD49R,.048X.016*%
%ADD26R,.045X.055*%
%ADD88C,.119*%
%ADD73R,.016X.048*%
%ADD42R,.13X.13*%
%ADD25R,.055X.045*%
%ADD119R,.06X.095*%
%ADD72R,.054X.075*%
%ADD59R,.054X.074*%
%AMMACRO52*
4,1,25,-.26575,.30715,
-.209725,.333219,
-.150024,.349164,
-.088461,.3545,
-.026908,.349064,
.032767,.333022,
.08875,.306861,
.139339,.271377,
.182998,.227647,
.2184,.177,
.244469,.120975,
.260414,.061274,
.26575,-.000289,
.260314,-.061842,
.244272,-.121517,
.218111,-.1775,
.182627,-.228089,
.138897,-.271748,
.08825,-.30715,
.032225,-.333219,
-.027476,-.349164,
-.089039,-.3545,
-.150592,-.349064,
-.210267,-.333022,
-.26575,-.30715,
-.26575,.30715,
0.0*
%
%ADD52MACRO52*%
%AMMACRO120*
4,1,25,.26575,.30715,
.209725,.333219,
.150024,.349164,
.088461,.3545,
.026908,.349064,
-.032767,.333022,
-.08875,.306861,
-.139339,.271377,
-.182998,.227647,
-.2184,.177,
-.244469,.120975,
-.260414,.061274,
-.26575,-.000289,
-.260314,-.061842,
-.244272,-.121517,
-.218111,-.1775,
-.182627,-.228089,
-.138897,-.271748,
-.08825,-.30715,
-.032225,-.333219,
.027476,-.349164,
.089039,-.3545,
.150592,-.349064,
.210267,-.333022,
.26575,-.30715,
.26575,.30715,
0.0*
%
%ADD120MACRO120*%
%ADD75R,.09X.095*%
%AMMACRO90*
4,1,40,-.0225,.007,
-.022378,.008389,
-.022018,.009736,
-.021428,.011,
-.020628,.012142,
-.019642,.013128,
-.0185,.013928,
-.017236,.014518,
-.015889,.014878,
-.0145,.015,
.0145,.015,
.015889,.014878,
.017236,.014518,
.0185,.013928,
.019642,.013128,
.020628,.012142,
.021428,.011,
.022018,.009736,
.022378,.008389,
.0225,.007,
.0225,-.007,
.022378,-.008389,
.022018,-.009736,
.021428,-.011,
.020628,-.012142,
.019642,-.013128,
.0185,-.013928,
.017236,-.014518,
.015889,-.014878,
.0145,-.015,
-.0145,-.015,
-.015889,-.014878,
-.017236,-.014518,
-.0185,-.013928,
-.019642,-.013128,
-.020628,-.012142,
-.021428,-.011,
-.022018,-.009736,
-.022378,-.008389,
-.0225,-.007,
-.0225,.007,
0.0*
%
%ADD90MACRO90*%
%ADD86C,.375*%
%AMMACRO64*
4,1,40,-.008,.014,
.008,.014,
.008695,.013939,
.009368,.013759,
.01,.013464,
.010571,.013064,
.011064,.012571,
.011464,.012,
.011759,.011368,
.011939,.010695,
.012,.01,
.012,-.01,
.011939,-.010695,
.011759,-.011368,
.011464,-.012,
.011064,-.012571,
.010571,-.013064,
.01,-.013464,
.009368,-.013759,
.008695,-.013939,
.008,-.014,
-.008,-.014,
-.008695,-.013939,
-.009368,-.013759,
-.01,-.013464,
-.010571,-.013064,
-.011064,-.012571,
-.011464,-.012,
-.011759,-.011368,
-.011939,-.010695,
-.012,-.01,
-.012,.01,
-.011939,.010695,
-.011759,.011368,
-.011464,.012,
-.011064,.012571,
-.010571,.013064,
-.01,.013464,
-.009368,.013759,
-.008695,.013939,
-.008,.014,
0.0*
%
%ADD64MACRO64*%
%AMMACRO27*
4,1,40,.007,.0225,
.008389,.022378,
.009736,.022018,
.011,.021428,
.012142,.020628,
.013128,.019642,
.013928,.0185,
.014518,.017236,
.014878,.015889,
.015,.0145,
.015,-.0145,
.014878,-.015889,
.014518,-.017236,
.013928,-.0185,
.013128,-.019642,
.012142,-.020628,
.011,-.021428,
.009736,-.022018,
.008389,-.022378,
.007,-.0225,
-.007,-.0225,
-.008389,-.022378,
-.009736,-.022018,
-.011,-.021428,
-.012142,-.020628,
-.013128,-.019642,
-.013928,-.0185,
-.014518,-.017236,
-.014878,-.015889,
-.015,-.0145,
-.015,.0145,
-.014878,.015889,
-.014518,.017236,
-.013928,.0185,
-.013128,.019642,
-.012142,.020628,
-.011,.021428,
-.009736,.022018,
-.008389,.022378,
-.007,.0225,
.007,.0225,
0.0*
%
%ADD27MACRO27*%
%ADD24R,.045X.059*%
%ADD116R,.128X.128*%
%AMMACRO51*
4,1,40,-.008,-.012,
.008,-.012,
.008695,-.011939,
.009368,-.011759,
.01,-.011464,
.010571,-.011064,
.011064,-.010571,
.011464,-.01,
.011759,-.009368,
.011939,-.008695,
.012,-.008,
.012,.008,
.011939,.008695,
.011759,.009368,
.011464,.01,
.011064,.010571,
.010571,.011064,
.01,.011464,
.009368,.011759,
.008695,.011939,
.008,.012,
-.008,.012,
-.008695,.011939,
-.009368,.011759,
-.01,.011464,
-.010571,.011064,
-.011064,.010571,
-.011464,.01,
-.011759,.009368,
-.011939,.008695,
-.012,.008,
-.012,-.008,
-.011939,-.008695,
-.011759,-.009368,
-.011464,-.01,
-.011064,-.010571,
-.010571,-.011064,
-.01,-.011464,
-.009368,-.011759,
-.008695,-.011939,
-.008,-.012,
0.0*
%
%ADD51MACRO51*%
%AMMACRO18*
4,1,40,.012,-.008,
.012,.008,
.011939,.008695,
.011759,.009368,
.011464,.01,
.011064,.010571,
.010571,.011064,
.01,.011464,
.009368,.011759,
.008695,.011939,
.008,.012,
-.008,.012,
-.008695,.011939,
-.009368,.011759,
-.01,.011464,
-.010571,.011064,
-.011064,.010571,
-.011464,.01,
-.011759,.009368,
-.011939,.008695,
-.012,.008,
-.012,-.008,
-.011939,-.008695,
-.011759,-.009368,
-.011464,-.01,
-.011064,-.010571,
-.010571,-.011064,
-.01,-.011464,
-.009368,-.011759,
-.008695,-.011939,
-.008,-.012,
.008,-.012,
.008695,-.011939,
.009368,-.011759,
.01,-.011464,
.010571,-.011064,
.011064,-.010571,
.011464,-.01,
.011759,-.009368,
.011939,-.008695,
.012,-.008,
0.0*
%
%ADD18MACRO18*%
%AMMACRO15*
4,1,40,-.007,-.011,
.007,-.011,
.007695,-.010939,
.008368,-.010759,
.009,-.010464,
.009571,-.010064,
.010064,-.009571,
.010464,-.009,
.010759,-.008368,
.010939,-.007695,
.011,-.007,
.011,.007,
.010939,.007695,
.010759,.008368,
.010464,.009,
.010064,.009571,
.009571,.010064,
.009,.010464,
.008368,.010759,
.007695,.010939,
.007,.011,
-.007,.011,
-.007695,.010939,
-.008368,.010759,
-.009,.010464,
-.009571,.010064,
-.010064,.009571,
-.010464,.009,
-.010759,.008368,
-.010939,.007695,
-.011,.007,
-.011,-.007,
-.010939,-.007695,
-.010759,-.008368,
-.010464,-.009,
-.010064,-.009571,
-.009571,-.010064,
-.009,-.010464,
-.008368,-.010759,
-.007695,-.010939,
-.007,-.011,
0.0*
%
%ADD15MACRO15*%
%AMMACRO32*
4,1,40,-.011,.007,
-.011,-.007,
-.010939,-.007695,
-.010759,-.008368,
-.010464,-.009,
-.010064,-.009571,
-.009571,-.010064,
-.009,-.010464,
-.008368,-.010759,
-.007695,-.010939,
-.007,-.011,
.007,-.011,
.007695,-.010939,
.008368,-.010759,
.009,-.010464,
.009571,-.010064,
.010064,-.009571,
.010464,-.009,
.010759,-.008368,
.010939,-.007695,
.011,-.007,
.011,.007,
.010939,.007695,
.010759,.008368,
.010464,.009,
.010064,.009571,
.009571,.010064,
.009,.010464,
.008368,.010759,
.007695,.010939,
.007,.011,
-.007,.011,
-.007695,.010939,
-.008368,.010759,
-.009,.010464,
-.009571,.010064,
-.010064,.009571,
-.010464,.009,
-.010759,.008368,
-.010939,.007695,
-.011,.007,
0.0*
%
%ADD32MACRO32*%
%AMMACRO85*
4,1,6,-.0135,.025,
.0065,.005,
.0135,.005,
.0135,-.005,
.0065,-.005,
-.0135,-.025,
-.0135,.025,
0.0*
%
%ADD85MACRO85*%
%AMMACRO77*
4,1,40,.013,.017,
-.013,.017,
-.013695,.016939,
-.014368,.016759,
-.015,.016464,
-.015571,.016064,
-.016064,.015571,
-.016464,.015,
-.016759,.014368,
-.016939,.013695,
-.017,.013,
-.017,-.013,
-.016939,-.013695,
-.016759,-.014368,
-.016464,-.015,
-.016064,-.015571,
-.015571,-.016064,
-.015,-.016464,
-.014368,-.016759,
-.013695,-.016939,
-.013,-.017,
.013,-.017,
.013695,-.016939,
.014368,-.016759,
.015,-.016464,
.015571,-.016064,
.016064,-.015571,
.016464,-.015,
.016759,-.014368,
.016939,-.013695,
.017,-.013,
.017,.013,
.016939,.013695,
.016759,.014368,
.016464,.015,
.016064,.015571,
.015571,.016064,
.015,.016464,
.014368,.016759,
.013695,.016939,
.013,.017,
0.0*
%
%ADD77MACRO77*%
%AMMACRO36*
4,1,40,.017,-.013,
.017,.013,
.016939,.013695,
.016759,.014368,
.016464,.015,
.016064,.015571,
.015571,.016064,
.015,.016464,
.014368,.016759,
.013695,.016939,
.013,.017,
-.013,.017,
-.013695,.016939,
-.014368,.016759,
-.015,.016464,
-.015571,.016064,
-.016064,.015571,
-.016464,.015,
-.016759,.014368,
-.016939,.013695,
-.017,.013,
-.017,-.013,
-.016939,-.013695,
-.016759,-.014368,
-.016464,-.015,
-.016064,-.015571,
-.015571,-.016064,
-.015,-.016464,
-.014368,-.016759,
-.013695,-.016939,
-.013,-.017,
.013,-.017,
.013695,-.016939,
.014368,-.016759,
.015,-.016464,
.015571,-.016064,
.016064,-.015571,
.016464,-.015,
.016759,-.014368,
.016939,-.013695,
.017,-.013,
0.0*
%
%ADD36MACRO36*%
%AMMACRO67*
4,1,6,-.005,-.0135,
-.005,-.0065,
-.025,.0135,
.025,.0135,
.005,-.0065,
.005,-.0135,
-.005,-.0135,
0.0*
%
%ADD67MACRO67*%
%AMMACRO50*
4,1,40,-.008,-.012,
.008,-.012,
.008695,-.011939,
.009368,-.011759,
.01,-.011464,
.010571,-.011064,
.011064,-.010571,
.011464,-.01,
.011759,-.009368,
.011939,-.008695,
.012,-.008,
.012,.008,
.011939,.008695,
.011759,.009368,
.011464,.01,
.011064,.010571,
.010571,.011064,
.01,.011464,
.009368,.011759,
.008695,.011939,
.008,.012,
-.008,.012,
-.008695,.011939,
-.009368,.011759,
-.01,.011464,
-.010571,.011064,
-.011064,.010571,
-.011464,.01,
-.011759,.009368,
-.011939,.008695,
-.012,.008,
-.012,-.008,
-.011939,-.008695,
-.011759,-.009368,
-.011464,-.01,
-.011064,-.010571,
-.010571,-.011064,
-.01,-.011464,
-.009368,-.011759,
-.008695,-.011939,
-.008,-.012,
0.0*
%
%ADD50MACRO50*%
%AMMACRO17*
4,1,40,.012,-.008,
.012,.008,
.011939,.008695,
.011759,.009368,
.011464,.01,
.011064,.010571,
.010571,.011064,
.01,.011464,
.009368,.011759,
.008695,.011939,
.008,.012,
-.008,.012,
-.008695,.011939,
-.009368,.011759,
-.01,.011464,
-.010571,.011064,
-.011064,.010571,
-.011464,.01,
-.011759,.009368,
-.011939,.008695,
-.012,.008,
-.012,-.008,
-.011939,-.008695,
-.011759,-.009368,
-.011464,-.01,
-.011064,-.010571,
-.010571,-.011064,
-.01,-.011464,
-.009368,-.011759,
-.008695,-.011939,
-.008,-.012,
.008,-.012,
.008695,-.011939,
.009368,-.011759,
.01,-.011464,
.010571,-.011064,
.011064,-.010571,
.011464,-.01,
.011759,-.009368,
.011939,-.008695,
.012,-.008,
0.0*
%
%ADD17MACRO17*%
%AMMACRO16*
4,1,40,-.007,-.011,
.007,-.011,
.007695,-.010939,
.008368,-.010759,
.009,-.010464,
.009571,-.010064,
.010064,-.009571,
.010464,-.009,
.010759,-.008368,
.010939,-.007695,
.011,-.007,
.011,.007,
.010939,.007695,
.010759,.008368,
.010464,.009,
.010064,.009571,
.009571,.010064,
.009,.010464,
.008368,.010759,
.007695,.010939,
.007,.011,
-.007,.011,
-.007695,.010939,
-.008368,.010759,
-.009,.010464,
-.009571,.010064,
-.010064,.009571,
-.010464,.009,
-.010759,.008368,
-.010939,.007695,
-.011,.007,
-.011,-.007,
-.010939,-.007695,
-.010759,-.008368,
-.010464,-.009,
-.010064,-.009571,
-.009571,-.010064,
-.009,-.010464,
-.008368,-.010759,
-.007695,-.010939,
-.007,-.011,
0.0*
%
%ADD16MACRO16*%
%AMMACRO33*
4,1,40,-.011,.007,
-.011,-.007,
-.010939,-.007695,
-.010759,-.008368,
-.010464,-.009,
-.010064,-.009571,
-.009571,-.010064,
-.009,-.010464,
-.008368,-.010759,
-.007695,-.010939,
-.007,-.011,
.007,-.011,
.007695,-.010939,
.008368,-.010759,
.009,-.010464,
.009571,-.010064,
.010064,-.009571,
.010464,-.009,
.010759,-.008368,
.010939,-.007695,
.011,-.007,
.011,.007,
.010939,.007695,
.010759,.008368,
.010464,.009,
.010064,.009571,
.009571,.010064,
.009,.010464,
.008368,.010759,
.007695,.010939,
.007,.011,
-.007,.011,
-.007695,.010939,
-.008368,.010759,
-.009,.010464,
-.009571,.010064,
-.010064,.009571,
-.010464,.009,
-.010759,.008368,
-.010939,.007695,
-.011,.007,
0.0*
%
%ADD33MACRO33*%
%ADD122C,.006*%
G75*
%LPD*%
G75*
G36*
G01X40400Y138185D02*
X31850D01*
Y129235D01*
X40400D01*
Y138185D01*
G37*
G36*
G01X51550D02*
X43000D01*
Y129235D01*
X51550D01*
Y138185D01*
G37*
G36*
G01X40400Y126635D02*
X31850D01*
Y117685D01*
X40400D01*
Y126635D01*
G37*
G36*
G01X51550D02*
X43000D01*
Y117685D01*
X51550D01*
Y126635D01*
G37*
G54D100*
X562460Y462070D03*
Y471070D03*
G54D110*
X702000Y347771D03*
X678452D03*
G54D101*
X634216Y47468D03*
Y25268D03*
X651536Y47468D03*
X649961D03*
X648386D03*
X646811D03*
X645236D03*
X643661D03*
X642091D03*
X640516D03*
X638941D03*
X637366D03*
X635791D03*
Y25268D03*
X637366D03*
X638941D03*
X640516D03*
X642091D03*
X643661D03*
X645236D03*
X646811D03*
X648386D03*
X649961D03*
X651536D03*
G54D120*
X780495Y517441D03*
G54D102*
X623566Y173443D03*
X627464D03*
X623566Y179499D03*
X627464D03*
G54D111*
X690890Y419020D03*
X687015Y411520D03*
X694765D03*
X701325Y420610D03*
X709075D03*
X734040Y441340D03*
X730165Y433840D03*
X737915D03*
X719850Y437470D03*
X715975Y429970D03*
X723725D03*
X705200Y428110D03*
G54D112*
X673161Y371204D03*
Y367267D03*
X662745Y369236D03*
G54D121*
X765018Y301111D03*
Y303671D03*
Y306231D03*
Y308791D03*
X781198D03*
Y306231D03*
Y303671D03*
Y301111D03*
G54D103*
X621320Y299289D03*
Y297319D03*
Y295354D03*
X605020D03*
Y297319D03*
Y299289D03*
X614220Y361815D03*
X605020D03*
X621320Y341633D03*
Y339668D03*
Y337698D03*
Y335728D03*
Y333763D03*
X605020D03*
Y335728D03*
Y337698D03*
Y339668D03*
Y341633D03*
X621320Y303224D03*
Y301259D03*
X605020D03*
Y303224D03*
X614220Y367725D03*
Y365755D03*
Y363785D03*
X605020D03*
Y365755D03*
Y367725D03*
X614220Y390105D03*
Y388135D03*
Y386165D03*
Y384195D03*
X605020D03*
Y386165D03*
Y388135D03*
Y390105D03*
X762337Y278194D03*
Y280164D03*
Y282134D03*
Y284104D03*
X771537D03*
Y282134D03*
Y280164D03*
Y278194D03*
G54D10*
X15812Y-86244D03*
X27058Y25484D03*
X81539Y542850D03*
X411652Y539991D03*
X812711Y-86834D03*
X798456Y26432D03*
G54D122*
G01X121778Y-377522D02*
X122652Y-376647D01*
X123307Y-375189D01*
X123744Y-373146D01*
X123307Y-371397D01*
X122434Y-370230D01*
X120905Y-369355D01*
X115010D01*
Y-386855D01*
X122215D01*
X123744Y-385689D01*
X124617Y-383938D01*
X125054Y-381897D01*
X124617Y-379855D01*
X123307Y-378105D01*
X121778Y-377522D01*
X115010D01*
G01X134475Y-386855D02*
Y-375189D01*
G01Y-377522D02*
X135567Y-376355D01*
X136659Y-375480D01*
X138187Y-375189D01*
X139278Y-375480D01*
X140589Y-376355D01*
G01X150447Y-392105D02*
X151757Y-392688D01*
X153504Y-392105D01*
X154595Y-390939D01*
X155469Y-389480D01*
X156778Y-384814D01*
X159617Y-375189D01*
G01X152630D02*
X156778Y-384814D01*
G01X176025Y-376647D02*
X174497Y-375480D01*
X173187Y-375189D01*
X171440Y-375772D01*
X170130Y-376938D01*
X169257Y-378980D01*
X169038Y-381022D01*
X169257Y-383064D01*
X170130Y-384814D01*
X171440Y-386272D01*
X173187Y-386855D01*
X174715Y-386272D01*
X176025Y-385105D01*
G01X186757Y-378980D02*
X193744D01*
X193089Y-376938D01*
X191997Y-375772D01*
X190469Y-375189D01*
X188940Y-375480D01*
X187630Y-376355D01*
X186757Y-378397D01*
X186320Y-380147D01*
Y-381897D01*
X186757Y-383647D01*
X187849Y-385397D01*
X189159Y-386563D01*
X190687Y-386855D01*
X192215Y-386272D01*
X193744Y-384522D01*
G01X229835Y-370814D02*
X228525Y-369938D01*
X226997Y-369355D01*
X225250D01*
X223285Y-370230D01*
X221757Y-371688D01*
X220665Y-373439D01*
X219792Y-376355D01*
X219573Y-378980D01*
X220010Y-381605D01*
X220665Y-383355D01*
X221975Y-385105D01*
X223504Y-386272D01*
X225032Y-386855D01*
X226560D01*
X228089Y-386272D01*
X229399Y-385397D01*
X230491Y-384231D01*
G01X246462Y-386855D02*
Y-375189D01*
G01Y-377230D02*
X245589Y-376064D01*
X244278Y-375480D01*
X242750Y-375189D01*
X241222Y-375772D01*
X239912Y-376938D01*
X239038Y-378688D01*
X238602Y-381022D01*
X239038Y-383355D01*
X239912Y-385105D01*
X241222Y-386272D01*
X242750Y-386855D01*
X244278Y-386563D01*
X245589Y-385689D01*
X246462Y-384522D01*
G01X256320Y-386855D02*
Y-375189D01*
G01Y-378105D02*
X257194Y-376647D01*
X258504Y-375480D01*
X260250Y-375189D01*
X261778Y-375480D01*
X263089Y-376647D01*
X263744Y-378688D01*
Y-386855D01*
G01X272947Y-392105D02*
X274257Y-392688D01*
X276004Y-392105D01*
X277095Y-390939D01*
X277969Y-389480D01*
X279278Y-384814D01*
X282117Y-375189D01*
G01X275130D02*
X279278Y-384814D01*
G01X295032Y-386855D02*
X293722Y-386563D01*
X292412Y-385397D01*
X291538Y-383355D01*
X291102Y-381022D01*
X291538Y-378688D01*
X292412Y-376647D01*
X293722Y-375480D01*
X295032Y-375189D01*
X296342Y-375480D01*
X297652Y-376647D01*
X298525Y-378688D01*
X298744Y-381022D01*
X298525Y-383355D01*
X297652Y-385397D01*
X296342Y-386563D01*
X295032Y-386855D01*
G01X308820D02*
Y-375189D01*
G01Y-378105D02*
X309694Y-376647D01*
X311004Y-375480D01*
X312750Y-375189D01*
X314278Y-375480D01*
X315589Y-376647D01*
X316244Y-378688D01*
Y-386855D01*
G01X342947Y-384522D02*
X344694Y-385980D01*
X346659Y-386855D01*
X348405D01*
X350152Y-385980D01*
X351462Y-384522D01*
X352117Y-382480D01*
X351680Y-380439D01*
X350589Y-378688D01*
X348624Y-377522D01*
X346004Y-376938D01*
X344475Y-375772D01*
X343820Y-373730D01*
X344257Y-371688D01*
X345349Y-370230D01*
X346877Y-369355D01*
X348405D01*
X349934Y-369938D01*
X351244Y-371397D01*
G01X369835Y-370814D02*
X368525Y-369938D01*
X366997Y-369355D01*
X365250D01*
X363285Y-370230D01*
X361757Y-371688D01*
X360665Y-373439D01*
X359792Y-376355D01*
X359573Y-378980D01*
X360010Y-381605D01*
X360665Y-383355D01*
X361975Y-385105D01*
X363504Y-386272D01*
X365032Y-386855D01*
X366560D01*
X368089Y-386272D01*
X369399Y-385397D01*
X370491Y-384231D01*
G01X387335Y-370814D02*
X386025Y-369938D01*
X384497Y-369355D01*
X382750D01*
X380785Y-370230D01*
X379257Y-371688D01*
X378165Y-373439D01*
X377292Y-376355D01*
X377073Y-378980D01*
X377510Y-381605D01*
X378165Y-383355D01*
X379475Y-385105D01*
X381004Y-386272D01*
X382532Y-386855D01*
X384060D01*
X385589Y-386272D01*
X386899Y-385397D01*
X387991Y-384231D01*
G01X210605Y-341855D02*
Y-324355D01*
X216282Y-338938D01*
X221959Y-324355D01*
Y-341855D01*
G01X233782D02*
X232472Y-341563D01*
X231162Y-340397D01*
X230288Y-338355D01*
X229852Y-336022D01*
X230288Y-333688D01*
X231162Y-331647D01*
X232472Y-330480D01*
X233782Y-330189D01*
X235092Y-330480D01*
X236402Y-331647D01*
X237275Y-333688D01*
X237494Y-336022D01*
X237275Y-338355D01*
X236402Y-340397D01*
X235092Y-341563D01*
X233782Y-341855D01*
G01X255212Y-324355D02*
Y-341855D01*
G01Y-339231D02*
X254339Y-340689D01*
X253028Y-341563D01*
X251500Y-341855D01*
X249754Y-341272D01*
X248444Y-339814D01*
X247570Y-338064D01*
X247352Y-336022D01*
X247570Y-333980D01*
X248444Y-332230D01*
X249754Y-330772D01*
X251500Y-330189D01*
X253028Y-330480D01*
X254120Y-331064D01*
X255212Y-332230D01*
G01X265507Y-333980D02*
X272494D01*
X271839Y-331938D01*
X270747Y-330772D01*
X269219Y-330189D01*
X267690Y-330480D01*
X266380Y-331355D01*
X265507Y-333397D01*
X265070Y-335147D01*
Y-336897D01*
X265507Y-338647D01*
X266599Y-340397D01*
X267909Y-341563D01*
X269437Y-341855D01*
X270965Y-341272D01*
X272494Y-339522D01*
G01X286282Y-341855D02*
Y-324355D01*
G01X566882Y-386855D02*
Y-369355D01*
X564262Y-372855D01*
G01Y-386855D02*
X569502D01*
G01X580234Y-379564D02*
X581762Y-377522D01*
X583072Y-376355D01*
X584819Y-375772D01*
X586347Y-376355D01*
X587439Y-377522D01*
X588312Y-379272D01*
X588530Y-381313D01*
X588312Y-383064D01*
X587439Y-384814D01*
X586128Y-386272D01*
X584600Y-386855D01*
X582854Y-386272D01*
X581325Y-384522D01*
X580452Y-381897D01*
X580234Y-378980D01*
X580670Y-375189D01*
X581325Y-373146D01*
X582417Y-371105D01*
X583945Y-369647D01*
X585474Y-369355D01*
X587002Y-369938D01*
X588094Y-371397D01*
G01X597079Y-383355D02*
X598388Y-385397D01*
X600135Y-386563D01*
X602100Y-386855D01*
X603847Y-386563D01*
X605594Y-385105D01*
X606685Y-383355D01*
X606904Y-381605D01*
X606467Y-379564D01*
X604939Y-378105D01*
X603410Y-377522D01*
X601445D01*
G01X603410D02*
X604720Y-376647D01*
X605812Y-375189D01*
X606249Y-373439D01*
X605812Y-371688D01*
X604720Y-370230D01*
X602755Y-369355D01*
X600790Y-369647D01*
X598825Y-370814D01*
G01X619382Y-386855D02*
Y-369355D01*
X616762Y-372855D01*
G01Y-386855D02*
X622002D01*
G01X632734Y-379564D02*
X634262Y-377522D01*
X635572Y-376355D01*
X637319Y-375772D01*
X638847Y-376355D01*
X639939Y-377522D01*
X640812Y-379272D01*
X641030Y-381313D01*
X640812Y-383064D01*
X639939Y-384814D01*
X638628Y-386272D01*
X637100Y-386855D01*
X635354Y-386272D01*
X633825Y-384522D01*
X632952Y-381897D01*
X632734Y-378980D01*
X633170Y-375189D01*
X633825Y-373146D01*
X634917Y-371105D01*
X636445Y-369647D01*
X637974Y-369355D01*
X639502Y-369938D01*
X640594Y-371397D01*
G01X553765Y-341855D02*
Y-324355D01*
X559005D01*
X560752Y-325230D01*
X562062Y-327272D01*
X562499Y-329605D01*
X562062Y-331938D01*
X560970Y-333688D01*
X559005Y-334564D01*
X553765D01*
G01X580435Y-325814D02*
X579125Y-324938D01*
X577597Y-324355D01*
X575850D01*
X573885Y-325230D01*
X572357Y-326688D01*
X571265Y-328439D01*
X570392Y-331355D01*
X570173Y-333980D01*
X570610Y-336605D01*
X571265Y-338355D01*
X572575Y-340105D01*
X574104Y-341272D01*
X575632Y-341855D01*
X577160D01*
X578689Y-341272D01*
X579999Y-340397D01*
X581091Y-339231D01*
G01X594878Y-332522D02*
X595752Y-331647D01*
X596407Y-330189D01*
X596844Y-328146D01*
X596407Y-326397D01*
X595534Y-325230D01*
X594005Y-324355D01*
X588110D01*
Y-341855D01*
X595315D01*
X596844Y-340689D01*
X597717Y-338938D01*
X598154Y-336897D01*
X597717Y-334855D01*
X596407Y-333105D01*
X594878Y-332522D01*
X588110D01*
G01X604082Y-347688D02*
X617182D01*
G01X623110Y-341855D02*
Y-324355D01*
X633154Y-341855D01*
Y-324355D01*
G01X645632Y-341855D02*
X643885Y-341563D01*
X642357Y-340397D01*
X641047Y-338647D01*
X640173Y-336605D01*
X639737Y-334272D01*
Y-331938D01*
X640173Y-329605D01*
X641047Y-327563D01*
X642357Y-325814D01*
X643885Y-324647D01*
X645632Y-324355D01*
X647378Y-324647D01*
X648907Y-325814D01*
X650217Y-327563D01*
X651091Y-329605D01*
X651527Y-331938D01*
Y-334272D01*
X651091Y-336605D01*
X650217Y-338647D01*
X648907Y-340397D01*
X647378Y-341563D01*
X645632Y-341855D01*
G01X696473Y-324355D02*
X701932Y-341855D01*
X707391Y-324355D01*
G01X723799Y-341855D02*
X715065D01*
Y-324355D01*
X723799D01*
G01X720305Y-332813D02*
X715065D01*
G01X732565Y-341855D02*
Y-324355D01*
X738024D01*
X739770Y-325230D01*
X740862Y-326397D01*
X741299Y-328730D01*
X740862Y-331064D01*
X739552Y-332522D01*
X738024Y-333397D01*
X732565D01*
G01X738024D02*
X741299Y-341855D01*
G01X754432Y-342438D02*
X753995Y-342147D01*
Y-341563D01*
X754432Y-341272D01*
X754869Y-341563D01*
Y-342147D01*
X754432Y-342438D01*
G01X728182Y-386855D02*
Y-369355D01*
X725562Y-372855D01*
G01Y-386855D02*
X730802D01*
G01X834382Y-369355D02*
Y-386855D01*
G01X829360Y-369355D02*
X839404D01*
G01X846205Y-386855D02*
Y-369355D01*
X851882Y-383938D01*
X857559Y-369355D01*
Y-386855D01*
G01X863923D02*
X869382Y-369355D01*
X874841Y-386855D01*
G01X872875Y-380730D02*
X865888D01*
G01X882297Y-384522D02*
X884044Y-385980D01*
X886009Y-386855D01*
X887755D01*
X889502Y-385980D01*
X890812Y-384522D01*
X891467Y-382480D01*
X891030Y-380439D01*
X889939Y-378688D01*
X887974Y-377522D01*
X885354Y-376938D01*
X883825Y-375772D01*
X883170Y-373730D01*
X883607Y-371688D01*
X884699Y-370230D01*
X886227Y-369355D01*
X887755D01*
X889284Y-369938D01*
X890594Y-371397D01*
G01X899579Y-386855D02*
Y-369355D01*
G01X907875D02*
X899579Y-380147D01*
G01X909185Y-386855D02*
X903290Y-375189D01*
G01X830015Y-324355D02*
Y-341855D01*
X838749D01*
G01X855812D02*
Y-330189D01*
G01Y-332230D02*
X854939Y-331064D01*
X853628Y-330480D01*
X852100Y-330189D01*
X850572Y-330772D01*
X849262Y-331938D01*
X848388Y-333688D01*
X847952Y-336022D01*
X848388Y-338355D01*
X849262Y-340105D01*
X850572Y-341272D01*
X852100Y-341855D01*
X853628Y-341563D01*
X854939Y-340689D01*
X855812Y-339522D01*
G01X864797Y-347105D02*
X866107Y-347688D01*
X867854Y-347105D01*
X868945Y-345939D01*
X869819Y-344480D01*
X871128Y-339814D01*
X873967Y-330189D01*
G01X866980D02*
X871128Y-339814D01*
G01X883607Y-333980D02*
X890594D01*
X889939Y-331938D01*
X888847Y-330772D01*
X887319Y-330189D01*
X885790Y-330480D01*
X884480Y-331355D01*
X883607Y-333397D01*
X883170Y-335147D01*
Y-336897D01*
X883607Y-338647D01*
X884699Y-340397D01*
X886009Y-341563D01*
X887537Y-341855D01*
X889065Y-341272D01*
X890594Y-339522D01*
G01X901325Y-341855D02*
Y-330189D01*
G01Y-332522D02*
X902417Y-331355D01*
X903509Y-330480D01*
X905037Y-330189D01*
X906128Y-330480D01*
X907439Y-331355D01*
G01X994432Y-386855D02*
X992685Y-386563D01*
X991157Y-385397D01*
X989847Y-383647D01*
X988973Y-381605D01*
X988537Y-379272D01*
Y-376938D01*
X988973Y-374605D01*
X989847Y-372563D01*
X991157Y-370814D01*
X992685Y-369647D01*
X994432Y-369355D01*
X996178Y-369647D01*
X997707Y-370814D01*
X999017Y-372563D01*
X999891Y-374605D01*
X1000327Y-376938D01*
Y-379272D01*
X999891Y-381605D01*
X999017Y-383647D01*
X997707Y-385397D01*
X996178Y-386563D01*
X994432Y-386855D01*
G01X996178Y-382188D02*
X998799Y-386855D01*
G01X1007129Y-369355D02*
Y-381897D01*
X1008002Y-384522D01*
X1009749Y-386272D01*
X1011932Y-386855D01*
X1014115Y-386272D01*
X1015862Y-384522D01*
X1016735Y-381897D01*
Y-369355D01*
G01X1026812D02*
X1032052D01*
G01X1029432D02*
Y-386855D01*
G01X1026812D02*
X1032052D01*
G01X1041910D02*
Y-369355D01*
X1051954Y-386855D01*
Y-369355D01*
G01X1069235Y-370814D02*
X1067925Y-369938D01*
X1066397Y-369355D01*
X1064650D01*
X1062685Y-370230D01*
X1061157Y-371688D01*
X1060065Y-373439D01*
X1059192Y-376355D01*
X1058973Y-378980D01*
X1059410Y-381605D01*
X1060065Y-383355D01*
X1061375Y-385105D01*
X1062904Y-386272D01*
X1064432Y-386855D01*
X1065960D01*
X1067489Y-386272D01*
X1068799Y-385397D01*
X1069891Y-384231D01*
G01X1081932Y-386855D02*
Y-378980D01*
X1077565Y-369355D01*
G01X1086299D02*
X1081932Y-378980D01*
G01X972129Y-341855D02*
Y-324355D01*
X976495D01*
X978242Y-325230D01*
X979552Y-326397D01*
X980644Y-328146D01*
X981517Y-330189D01*
X981735Y-333105D01*
X981517Y-336022D01*
X980644Y-338064D01*
X979552Y-339814D01*
X978242Y-340980D01*
X976495Y-341855D01*
X972129D01*
G01X991157Y-333980D02*
X998144D01*
X997489Y-331938D01*
X996397Y-330772D01*
X994869Y-330189D01*
X993340Y-330480D01*
X992030Y-331355D01*
X991157Y-333397D01*
X990720Y-335147D01*
Y-336897D01*
X991157Y-338647D01*
X992249Y-340397D01*
X993559Y-341563D01*
X995087Y-341855D01*
X996615Y-341272D01*
X998144Y-339522D01*
G01X1008657Y-339814D02*
X1009749Y-340980D01*
X1011277Y-341855D01*
X1012587D01*
X1013897Y-341272D01*
X1014770Y-340397D01*
X1015207Y-339231D01*
X1014989Y-337480D01*
X1014115Y-336605D01*
X1010185Y-334855D01*
X1009312Y-332813D01*
X1009749Y-331355D01*
X1010622Y-330480D01*
X1011932Y-330189D01*
X1013242Y-330480D01*
X1014552Y-331355D01*
G01X1029432Y-330189D02*
Y-341855D01*
G01Y-325522D02*
X1028995Y-325230D01*
Y-324647D01*
X1029432Y-324355D01*
X1029869Y-324647D01*
Y-325230D01*
X1029432Y-325522D01*
G01X1043875Y-346230D02*
X1045404Y-347397D01*
X1047150Y-347688D01*
X1048678Y-347397D01*
X1049989Y-345939D01*
X1050862Y-343897D01*
Y-330189D01*
G01Y-332522D02*
X1049989Y-331355D01*
X1048678Y-330480D01*
X1047150Y-330189D01*
X1045404Y-330772D01*
X1044312Y-331938D01*
X1043438Y-333980D01*
X1043002Y-336022D01*
X1043220Y-337772D01*
X1044094Y-339814D01*
X1045404Y-341272D01*
X1047150Y-341855D01*
X1048460Y-341563D01*
X1049989Y-340397D01*
X1050862Y-339231D01*
G01X1060720Y-341855D02*
Y-330189D01*
G01Y-333105D02*
X1061594Y-331647D01*
X1062904Y-330480D01*
X1064650Y-330189D01*
X1066178Y-330480D01*
X1067489Y-331647D01*
X1068144Y-333688D01*
Y-341855D01*
G01X1078657Y-333980D02*
X1085644D01*
X1084989Y-331938D01*
X1083897Y-330772D01*
X1082369Y-330189D01*
X1080840Y-330480D01*
X1079530Y-331355D01*
X1078657Y-333397D01*
X1078220Y-335147D01*
Y-336897D01*
X1078657Y-338647D01*
X1079749Y-340397D01*
X1081059Y-341563D01*
X1082587Y-341855D01*
X1084115Y-341272D01*
X1085644Y-339522D01*
G01X1096375Y-341855D02*
Y-330189D01*
G01Y-332522D02*
X1097467Y-331355D01*
X1098559Y-330480D01*
X1100087Y-330189D01*
X1101178Y-330480D01*
X1102489Y-331355D01*
G01X1143132Y-369355D02*
X1141385Y-369938D01*
X1140075Y-371397D01*
X1139202Y-373146D01*
X1138547Y-375480D01*
X1138329Y-378105D01*
X1138547Y-380730D01*
X1139202Y-383064D01*
X1140075Y-384814D01*
X1141385Y-386272D01*
X1143132Y-386855D01*
X1144878Y-386272D01*
X1146189Y-384814D01*
X1147062Y-383064D01*
X1147717Y-380730D01*
X1147935Y-378105D01*
X1147717Y-375480D01*
X1147062Y-373146D01*
X1146189Y-371397D01*
X1144878Y-369938D01*
X1143132Y-369355D01*
G01X1156484Y-379564D02*
X1158012Y-377522D01*
X1159322Y-376355D01*
X1161069Y-375772D01*
X1162597Y-376355D01*
X1163689Y-377522D01*
X1164562Y-379272D01*
X1164780Y-381313D01*
X1164562Y-383064D01*
X1163689Y-384814D01*
X1162378Y-386272D01*
X1160850Y-386855D01*
X1159104Y-386272D01*
X1157575Y-384522D01*
X1156702Y-381897D01*
X1156484Y-378980D01*
X1156920Y-375189D01*
X1157575Y-373146D01*
X1158667Y-371105D01*
X1160195Y-369647D01*
X1161724Y-369355D01*
X1163252Y-369938D01*
X1164344Y-371397D01*
G01X1174202Y-387438D02*
X1182062Y-369355D01*
G01X1191484Y-372272D02*
X1192794Y-370522D01*
X1194322Y-369647D01*
X1196069Y-369355D01*
X1198252Y-369938D01*
X1199780Y-371397D01*
X1200217Y-373146D01*
X1199999Y-374897D01*
X1199125Y-376355D01*
X1194759Y-379272D01*
X1192794Y-381313D01*
X1191484Y-384231D01*
X1191047Y-386855D01*
X1200217D01*
G01X1213132D02*
Y-369355D01*
X1210512Y-372855D01*
G01Y-386855D02*
X1215752D01*
G01X1226702Y-387438D02*
X1234562Y-369355D01*
G01X1243984Y-372272D02*
X1245294Y-370522D01*
X1246822Y-369647D01*
X1248569Y-369355D01*
X1250752Y-369938D01*
X1252280Y-371397D01*
X1252717Y-373146D01*
X1252499Y-374897D01*
X1251625Y-376355D01*
X1247259Y-379272D01*
X1245294Y-381313D01*
X1243984Y-384231D01*
X1243547Y-386855D01*
X1252717D01*
G01X1265632Y-369355D02*
X1263885Y-369938D01*
X1262575Y-371397D01*
X1261702Y-373146D01*
X1261047Y-375480D01*
X1260829Y-378105D01*
X1261047Y-380730D01*
X1261702Y-383064D01*
X1262575Y-384814D01*
X1263885Y-386272D01*
X1265632Y-386855D01*
X1267378Y-386272D01*
X1268689Y-384814D01*
X1269562Y-383064D01*
X1270217Y-380730D01*
X1270435Y-378105D01*
X1270217Y-375480D01*
X1269562Y-373146D01*
X1268689Y-371397D01*
X1267378Y-369938D01*
X1265632Y-369355D01*
G01X1283132Y-386855D02*
Y-369355D01*
X1280512Y-372855D01*
G01Y-386855D02*
X1285752D01*
G01X1300195D02*
X1300632Y-383064D01*
X1301287Y-379855D01*
X1302160Y-376938D01*
X1303252Y-373730D01*
X1304999Y-369355D01*
X1296265D01*
G01X1190829Y-341855D02*
Y-324355D01*
X1195195D01*
X1196942Y-325230D01*
X1198252Y-326397D01*
X1199344Y-328146D01*
X1200217Y-330189D01*
X1200435Y-333105D01*
X1200217Y-336022D01*
X1199344Y-338064D01*
X1198252Y-339814D01*
X1196942Y-340980D01*
X1195195Y-341855D01*
X1190829D01*
G01X1217062D02*
Y-330189D01*
G01Y-332230D02*
X1216189Y-331064D01*
X1214878Y-330480D01*
X1213350Y-330189D01*
X1211822Y-330772D01*
X1210512Y-331938D01*
X1209638Y-333688D01*
X1209202Y-336022D01*
X1209638Y-338355D01*
X1210512Y-340105D01*
X1211822Y-341272D01*
X1213350Y-341855D01*
X1214878Y-341563D01*
X1216189Y-340689D01*
X1217062Y-339522D01*
G01X1230632Y-324355D02*
Y-341855D01*
G01X1227575Y-330189D02*
X1233689D01*
G01X1244857Y-333980D02*
X1251844D01*
X1251189Y-331938D01*
X1250097Y-330772D01*
X1248569Y-330189D01*
X1247040Y-330480D01*
X1245730Y-331355D01*
X1244857Y-333397D01*
X1244420Y-335147D01*
Y-336897D01*
X1244857Y-338647D01*
X1245949Y-340397D01*
X1247259Y-341563D01*
X1248787Y-341855D01*
X1250315Y-341272D01*
X1251844Y-339522D01*
G54D20*
X26500Y156700D03*
X49700Y394600D03*
X242733Y66711D03*
X223995Y66691D03*
X226200Y404600D03*
X275500Y405700D03*
X344891Y206040D03*
X691400Y391100D03*
X652200Y366500D03*
X757488Y297561D03*
X713150Y450195D03*
X778440Y278610D03*
X786560Y324630D03*
G54D104*
X632800Y341500D03*
X629200D03*
X632800Y302891D03*
X629200D03*
X693900Y302100D03*
X690300D03*
G54D11*
G01X-34018Y-300855D02*
G02I-12000J0D01*
G01X-39168D02*
G02I-6850J0D01*
G01X-30018D02*
X-62018D01*
G01X-30018Y-316855D02*
Y-396855D01*
G01D02*
X1320682D01*
G01X-30018Y-352355D02*
X1320682D01*
G01X-46018Y-316855D02*
Y-284855D01*
G01X-30018Y-316855D02*
X1320682D01*
G01X533182D02*
Y-396855D01*
G01X670682Y-316855D02*
Y-396855D01*
G01X785682Y-316855D02*
Y-396855D01*
G01X953182Y-316855D02*
Y-396855D01*
G01X1123182Y-316855D02*
Y-396855D01*
G01X1320682Y-316855D02*
Y-396855D01*
G01X1348682Y-300855D02*
G02I-12000J0D01*
G01X1343532D02*
G02I-6850J0D01*
G01X1336682Y-316855D02*
Y-284855D01*
G01X1352682Y-300855D02*
X1320682D01*
X15364Y5500D03*
X10364D03*
X5500Y10384D03*
Y15384D03*
Y20384D03*
Y25384D03*
Y30384D03*
Y35384D03*
Y40384D03*
Y45384D03*
Y50384D03*
Y55384D03*
Y60384D03*
Y65384D03*
Y70384D03*
Y75384D03*
Y80384D03*
Y85384D03*
Y90384D03*
Y95384D03*
Y100384D03*
Y105384D03*
Y110384D03*
Y115384D03*
Y120384D03*
Y125384D03*
Y130384D03*
Y135384D03*
Y140384D03*
Y145384D03*
Y150384D03*
Y155384D03*
Y160384D03*
Y165384D03*
Y170384D03*
Y175384D03*
Y180384D03*
Y185384D03*
Y190384D03*
Y195384D03*
Y200384D03*
Y205384D03*
Y210384D03*
Y215384D03*
Y220384D03*
Y225384D03*
Y230384D03*
Y235384D03*
Y240384D03*
Y245384D03*
Y250384D03*
Y255384D03*
Y260384D03*
Y265384D03*
Y270384D03*
Y275384D03*
Y280384D03*
Y285384D03*
Y290384D03*
Y295384D03*
Y300384D03*
Y305384D03*
Y310384D03*
Y315384D03*
Y320384D03*
Y325384D03*
Y330384D03*
Y335384D03*
Y340384D03*
Y345384D03*
Y350384D03*
Y355384D03*
Y360384D03*
Y365384D03*
Y370384D03*
Y375384D03*
Y380384D03*
Y385384D03*
Y390384D03*
Y395384D03*
Y400384D03*
Y405384D03*
Y410384D03*
Y415384D03*
Y420384D03*
Y425384D03*
Y430384D03*
Y435384D03*
Y440384D03*
Y445384D03*
Y450384D03*
Y455384D03*
Y460384D03*
Y465384D03*
Y470384D03*
Y475384D03*
Y480384D03*
Y485384D03*
Y530384D03*
Y525384D03*
Y520384D03*
Y515384D03*
Y510384D03*
Y505384D03*
Y490384D03*
Y495384D03*
Y500384D03*
Y535384D03*
Y540384D03*
Y545384D03*
Y550384D03*
Y555384D03*
Y560384D03*
X10266Y565366D03*
X15266D03*
X75364Y5500D03*
X70364D03*
X65364D03*
X60364D03*
X55364D03*
X50364D03*
X45364D03*
X40364D03*
X35364D03*
X30364D03*
X25364D03*
X20364D03*
X75119Y111166D03*
X20266Y565366D03*
X25266D03*
X30266D03*
X35266D03*
X40266D03*
X45266D03*
X50266D03*
X55266D03*
X60266D03*
X65266D03*
X70266D03*
X75266D03*
X95364Y5500D03*
X90364D03*
X85364D03*
X80364D03*
X105619Y111166D03*
X81119D03*
X87619D03*
X93619D03*
X99619D03*
X128580Y170810D03*
X122984Y170984D03*
X123200Y175800D03*
X125741Y166309D03*
X128459Y175658D03*
X140000Y204950D03*
X94080Y448470D03*
X80266Y565366D03*
X85266D03*
X90266D03*
X95266D03*
X100266D03*
X105266D03*
X110266D03*
X115266D03*
X120266D03*
X125266D03*
X130266D03*
X135266D03*
X200364Y5500D03*
X195364D03*
X190364D03*
X185364D03*
X180364D03*
X175364D03*
X170364D03*
X192830Y170500D03*
X197630D03*
X192830Y165700D03*
X197630D03*
X192830Y160900D03*
X197630D03*
X170900Y160500D03*
X151500D03*
X156300D03*
X161100D03*
X165900D03*
X198557Y153196D03*
X191900Y196100D03*
X196900D03*
X201700D03*
X196900Y200900D03*
X191900D03*
X196900Y205700D03*
X191900D03*
X196900Y210500D03*
X191900D03*
X201700Y205700D03*
Y200900D03*
X151500Y205000D03*
X156300D03*
X161100D03*
X165900D03*
X170900D03*
X178450Y203150D03*
X144800Y204950D03*
X177850Y324800D03*
X174995Y353588D03*
Y358388D03*
X165195D03*
X169995D03*
Y353588D03*
X197718Y350937D03*
Y355859D03*
X157650Y418100D03*
X160400Y422900D03*
X160550Y414100D03*
X177468Y417900D03*
X142865Y424021D03*
X143608Y415900D03*
X158067Y378857D03*
X160400Y427700D03*
Y432500D03*
X176311Y445493D03*
X176423Y440472D03*
X177421Y432909D03*
X177532Y426134D03*
X145392Y445207D03*
X145456Y440338D03*
X142991Y430900D03*
X200266Y565366D03*
X195266D03*
X190266D03*
X185266D03*
X180266D03*
X175266D03*
X140266D03*
X145266D03*
X150266D03*
X155266D03*
X160266D03*
X165266D03*
X170266D03*
X260364Y5500D03*
X255364D03*
X250364D03*
X245364D03*
X240364D03*
X235364D03*
X230364D03*
X225364D03*
X220364D03*
X215364D03*
X210364D03*
X205364D03*
X222700Y149300D03*
X227500D03*
X222700Y144500D03*
X227500D03*
X222700Y139700D03*
X227500D03*
X222700Y158900D03*
X227500D03*
X222700Y154100D03*
X227500D03*
X202430Y170500D03*
Y165700D03*
Y160900D03*
X253600Y139500D03*
Y134700D03*
X251800Y153600D03*
Y144000D03*
Y148800D03*
X258400Y134700D03*
Y139500D03*
X263200Y134700D03*
Y139500D03*
X222800Y204600D03*
X227600D03*
X222800Y219000D03*
X227600D03*
X222800Y214200D03*
X227600D03*
X222800Y209400D03*
X227600D03*
X222490Y235373D03*
X227290D03*
X222246Y229952D03*
X227046D03*
X222800Y223800D03*
X227600D03*
X253600Y230500D03*
Y225700D03*
Y220900D03*
X258400Y230500D03*
Y225700D03*
Y220900D03*
X263200Y230500D03*
Y225700D03*
Y220900D03*
X222460Y240264D03*
X227260D03*
X249204Y244103D03*
X254300Y357732D03*
X222818Y364806D03*
X222909Y371864D03*
X223000Y378246D03*
X246700Y418600D03*
X209052Y470198D03*
X213700Y448450D03*
X208900D03*
X203000Y451300D03*
X204252Y470198D03*
X204364Y478917D03*
X209164D03*
X212589Y494694D03*
X220589D03*
X216589Y489694D03*
X208589D03*
X224589D03*
X205266Y565366D03*
X210266D03*
X215266D03*
X220266D03*
X225266D03*
X230266D03*
X235266D03*
X240266D03*
X245266D03*
X250266D03*
X255266D03*
X260266D03*
X325364Y5500D03*
X320364D03*
X315364D03*
X310364D03*
X305364D03*
X300364D03*
X295364D03*
X290364D03*
X285364D03*
X280364D03*
X275364D03*
X270364D03*
X265364D03*
X295960Y148987D03*
Y154387D03*
X308907Y171800D03*
Y166400D03*
Y161000D03*
X287000Y117600D03*
Y125000D03*
X285500Y130400D03*
X290300D03*
X287300Y173000D03*
X292100D03*
X295650Y169554D03*
X295100Y130400D03*
X272800Y168000D03*
Y172800D03*
Y134700D03*
X268000Y165962D03*
X268064Y171792D03*
X268000Y158700D03*
Y153900D03*
Y134700D03*
Y139500D03*
Y144300D03*
Y149100D03*
X296200Y195900D03*
Y190500D03*
X308907Y215200D03*
Y220600D03*
Y226000D03*
Y231400D03*
Y236800D03*
Y209800D03*
Y188200D03*
Y199000D03*
Y204400D03*
Y177200D03*
Y193600D03*
Y182800D03*
X296400Y237950D03*
Y232550D03*
X295801Y210294D03*
X292600Y214500D03*
X287800D03*
X272800Y177600D03*
X268064Y184062D03*
X268000Y235300D03*
Y230500D03*
Y225700D03*
Y220900D03*
Y216000D03*
Y211200D03*
X268118Y191305D03*
X268000Y206400D03*
Y196800D03*
Y201600D03*
Y178062D03*
X308907Y242200D03*
X295879Y255540D03*
X291079D03*
X286279D03*
X266404Y249707D03*
X268000Y244900D03*
Y240100D03*
X276070Y395357D03*
X265266Y565366D03*
X270266D03*
X275266D03*
X280266D03*
X285266D03*
X290266D03*
X295266D03*
X300266D03*
X305266D03*
X310266D03*
X315266D03*
X320266D03*
X325266D03*
X330364Y5500D03*
X346700Y296333D03*
Y291533D03*
X350586Y495815D03*
X355523Y495025D03*
X360461Y494236D03*
X365398Y493446D03*
X370335Y492656D03*
X375272Y491866D03*
X380210Y491077D03*
X385169Y490563D03*
X329156Y545492D03*
Y540492D03*
Y535492D03*
Y530492D03*
Y525492D03*
Y520492D03*
Y515492D03*
Y560492D03*
Y555492D03*
Y550492D03*
X399606Y202756D03*
X395669D03*
X399606Y206693D03*
X395669D03*
X391732D03*
X399606Y210630D03*
X395669D03*
X391732D03*
X399606Y316930D03*
X395669D03*
X391732D03*
X399606Y320867D03*
X395669D03*
X391732D03*
X399606Y324804D03*
X395669D03*
X405169Y490563D03*
X410169D03*
X415169D03*
X420169D03*
X425169D03*
X430169D03*
X435169D03*
X440169D03*
X445146Y490850D03*
X450083Y491640D03*
X390169Y490563D03*
X395169D03*
X400169D03*
X509843Y202756D03*
X505906D03*
X509843Y206693D03*
X505906D03*
X509843Y210630D03*
X505906D03*
X509843Y316930D03*
X505906D03*
X509843Y320867D03*
X505906D03*
X509843Y324804D03*
X505906D03*
X505500Y464400D03*
Y469200D03*
Y474000D03*
X509500Y450800D03*
Y446000D03*
Y441200D03*
X469832Y494799D03*
X474769Y495589D03*
X455020Y492430D03*
X459958Y493219D03*
X464895Y494009D03*
X497636Y515532D03*
Y520532D03*
Y525532D03*
Y530532D03*
Y535532D03*
Y540532D03*
Y545532D03*
Y550532D03*
Y555532D03*
Y560532D03*
X502550Y565366D03*
X507550D03*
X512550D03*
X513780Y206693D03*
Y210630D03*
X570234Y298026D03*
X572634Y293526D03*
X513780Y316930D03*
Y320867D03*
X571300Y414800D03*
X567200Y407700D03*
X572062Y384378D03*
X527742Y425481D03*
X522942D03*
X518142D03*
X527742Y432481D03*
X522942D03*
X518142D03*
X529500Y471500D03*
X551400Y437800D03*
X545900D03*
X539800Y437900D03*
X517550Y565366D03*
X522550D03*
X527550D03*
X532550D03*
X537550D03*
X542550D03*
X547550D03*
X552550D03*
X557550D03*
X562550D03*
X567550D03*
X572550D03*
X591446Y6545D03*
X596446D03*
X601446D03*
X606446D03*
X611446D03*
X616446D03*
X621446D03*
X636446D03*
X631446D03*
X626446D03*
X576797Y113877D03*
X582554Y116361D03*
X575134Y298026D03*
X577534Y293526D03*
X580034Y298026D03*
X580900Y414800D03*
X576100D03*
X632150Y389100D03*
X576862Y384378D03*
X581087Y379569D03*
X576287D03*
X581692Y384378D03*
X628113Y428617D03*
X623313D03*
X618513D03*
X613713D03*
X605534Y480027D03*
X635000Y427784D03*
X619600Y446100D03*
X629200D03*
X624400D03*
X577550Y565366D03*
X582550D03*
X587550D03*
X592550D03*
X597550D03*
X602550D03*
X607550D03*
X612550D03*
X617550D03*
X622550D03*
X627550D03*
X632550D03*
X641446Y6545D03*
X646446D03*
X651446D03*
X696446D03*
X691446D03*
X661446D03*
X656446D03*
X686446D03*
X681446D03*
X676446D03*
X671446D03*
X666446D03*
X655964Y52248D03*
X675136Y268500D03*
X637705Y298765D03*
X642705D03*
X659977Y323082D03*
X664731Y324099D03*
X660115Y351977D03*
Y356777D03*
X664731Y343299D03*
X655500Y360000D03*
X660115Y361577D03*
X664731Y338499D03*
Y333699D03*
Y328899D03*
X659977Y342282D03*
Y332682D03*
Y347082D03*
Y337482D03*
Y327882D03*
X696900Y337800D03*
X697500Y358200D03*
X637705Y303765D03*
X642705D03*
X674700Y306300D03*
X679500D03*
Y311100D03*
X674700D03*
X679500Y315900D03*
X674700D03*
X665520Y307707D03*
Y312507D03*
X654642D03*
X654488Y317417D03*
X660100Y307500D03*
X654642Y307707D03*
X665478Y317527D03*
X684400Y400100D03*
X637550Y389050D03*
X655532Y425245D03*
X658032Y420245D03*
X653032D03*
X653200Y408800D03*
X694950Y477850D03*
Y473050D03*
X688500Y484400D03*
X675700Y468000D03*
Y463500D03*
X675400Y472300D03*
X659000Y428900D03*
X652200Y429100D03*
X639120Y462230D03*
X688500Y488600D03*
X637550Y565366D03*
X642550D03*
X647550D03*
X652550D03*
X657550D03*
X662550D03*
X667550D03*
X672550D03*
X677550D03*
X682550D03*
X687550D03*
X692550D03*
X697550D03*
X701446Y6545D03*
X742200Y340800D03*
Y345600D03*
X737400Y340800D03*
Y345600D03*
X732600Y331200D03*
Y336000D03*
Y340800D03*
Y355200D03*
Y350400D03*
Y345600D03*
X701100Y315900D03*
X705900D03*
X701100Y311100D03*
X705900D03*
Y306300D03*
X701100D03*
X714600Y338900D03*
Y348500D03*
Y343700D03*
X709800Y348500D03*
Y343700D03*
X706500Y337800D03*
X701700D03*
X707100Y358200D03*
X702300D03*
X704115Y414466D03*
Y409666D03*
Y404866D03*
Y400066D03*
X722100Y368300D03*
X717300D03*
X712500D03*
X742200Y380400D03*
Y370800D03*
Y375600D03*
X728700Y381000D03*
Y376200D03*
Y371400D03*
X722100Y363500D03*
X717300D03*
X712500D03*
X705900Y386900D03*
X711000Y395100D03*
X710900Y386800D03*
X706000Y395100D03*
X725247Y458974D03*
X724422Y464139D03*
X724400Y485200D03*
Y480400D03*
Y475600D03*
X740900Y476400D03*
Y469400D03*
Y461900D03*
X704340Y468062D03*
X705400Y477400D03*
X724400Y490200D03*
X702550Y565366D03*
X707550D03*
X712550D03*
X717550D03*
X722550D03*
X727550D03*
X732550D03*
X737550D03*
X742550D03*
X747550D03*
X752550D03*
X757550D03*
X821272Y49340D03*
Y44340D03*
Y39340D03*
Y34340D03*
Y29340D03*
Y24340D03*
Y19340D03*
Y14340D03*
Y9340D03*
X815364Y5500D03*
X810364D03*
X805364D03*
X800364D03*
X795364D03*
X790364D03*
X785364D03*
X780364D03*
X775364D03*
X770364D03*
X765364D03*
X821272Y114340D03*
Y109340D03*
Y104340D03*
Y99340D03*
Y94340D03*
Y89340D03*
Y84340D03*
Y79340D03*
Y74340D03*
Y69340D03*
Y64340D03*
Y59340D03*
Y54340D03*
Y174340D03*
Y169340D03*
Y164340D03*
Y159340D03*
Y154340D03*
Y149340D03*
Y144340D03*
Y139340D03*
Y134340D03*
Y129340D03*
Y124340D03*
Y119340D03*
Y234340D03*
Y229340D03*
Y224340D03*
Y219340D03*
Y214340D03*
Y209340D03*
Y204340D03*
Y199340D03*
Y194340D03*
Y189340D03*
Y184340D03*
Y179340D03*
X771083Y211784D03*
X821272Y299340D03*
Y294340D03*
Y289340D03*
Y284340D03*
Y279340D03*
Y274340D03*
Y269340D03*
Y264340D03*
Y259340D03*
Y254340D03*
Y249340D03*
Y244340D03*
Y239340D03*
Y359340D03*
Y354340D03*
Y349340D03*
Y344340D03*
Y339340D03*
Y334340D03*
Y329340D03*
Y324340D03*
Y319340D03*
Y314340D03*
Y309340D03*
Y304340D03*
Y424340D03*
Y419340D03*
Y414340D03*
Y409340D03*
Y404340D03*
Y399340D03*
Y394340D03*
Y389340D03*
Y384340D03*
Y379340D03*
Y374340D03*
Y369340D03*
Y364340D03*
Y484340D03*
Y479340D03*
Y474340D03*
Y469340D03*
Y464340D03*
Y459340D03*
Y454340D03*
Y449340D03*
Y444340D03*
Y439340D03*
Y434340D03*
Y429340D03*
Y504340D03*
Y509340D03*
Y514340D03*
Y519340D03*
Y524340D03*
Y529340D03*
Y549340D03*
Y544340D03*
Y539340D03*
Y534340D03*
Y499340D03*
Y494340D03*
Y489340D03*
X762550Y565366D03*
X767550D03*
X772550D03*
X777550D03*
X782550D03*
X787550D03*
X792550D03*
X797550D03*
X802550D03*
X807550D03*
X812550D03*
X817550D03*
X821272Y559340D03*
Y554340D03*
G54D113*
X665245Y373173D03*
G54D114*
X676311Y379078D03*
Y377110D03*
Y375141D03*
Y373173D03*
X659595Y379078D03*
Y375141D03*
Y377110D03*
G54D21*
X52607Y171752D03*
X56607D03*
X72800Y186600D03*
X25900Y207000D03*
X65500Y234500D03*
X45938Y235404D03*
X41938D03*
X64100Y187800D03*
X46500Y186900D03*
X50500D03*
X26600Y278900D03*
X27200Y305200D03*
X65500Y375500D03*
X22000Y375052D03*
X43000Y374933D03*
X73100Y375500D03*
X29900Y375052D03*
X50700Y374933D03*
X87300Y227100D03*
X89800Y186800D03*
X85795Y375126D03*
X93695D03*
X89600Y394600D03*
X195161Y131517D03*
X201139Y118095D03*
X156700Y136200D03*
X250791Y69127D03*
X238880Y70262D03*
X220227Y70215D03*
X238900Y287900D03*
X245800Y288000D03*
X219400Y287400D03*
X226600Y287900D03*
X260000D03*
X240200Y306800D03*
X258700Y304300D03*
X222000Y306700D03*
X255500Y419200D03*
X318050Y296600D03*
X267600Y287900D03*
X285400Y320800D03*
X283000Y409200D03*
X269500Y420200D03*
X343000Y305700D03*
X345121Y331450D03*
X370932Y323700D03*
X326083Y412566D03*
X412400Y343784D03*
X437500Y344200D03*
X427700Y344000D03*
X400300Y345100D03*
X469996Y354412D03*
X451400Y344200D03*
X460327Y344201D03*
X464327D03*
X482427Y358374D03*
X486627D03*
X497900Y345300D03*
X502700D03*
X507337Y345263D03*
X478298Y358254D03*
X480700Y344200D03*
X522000Y354850D03*
X512754Y345184D03*
X573570Y463680D03*
X590350Y330450D03*
X618900Y322800D03*
X631800Y322700D03*
X629370Y460030D03*
X586720Y476380D03*
X664301Y35265D03*
X664000Y57200D03*
X643492Y90136D03*
X639392D03*
X682700Y237200D03*
X695600D03*
X695100Y381700D03*
X675831Y396033D03*
X670610Y418830D03*
X675380Y457860D03*
X667900Y446600D03*
X755523Y93515D03*
X751023D03*
X699600Y237200D03*
X743600Y224400D03*
X739500D03*
X734286Y224423D03*
X726656Y231898D03*
X719300Y220900D03*
X759651Y266807D03*
X751470Y310720D03*
X700200Y381700D03*
X763840Y266710D03*
X782800Y328170D03*
G54D105*
X629400Y405234D03*
X609400D03*
X619400Y417046D03*
X599400D03*
X761520Y350206D03*
X781520D03*
X771520Y338394D03*
X791520D03*
G54D12*
X37700Y64400D03*
X86150Y441700D03*
X365450Y179154D03*
X552000Y368500D03*
X630600Y221100D03*
X762300Y106300D03*
X737400Y485700D03*
G54D30*
X26634Y150171D03*
X35000Y165500D03*
X58962Y161005D03*
X64862Y152205D03*
X58470Y118520D03*
X22839Y163817D03*
X34380Y203183D03*
X74700Y226300D03*
X69000Y226200D03*
X23453Y180973D03*
X76425Y191400D03*
X41617Y183405D03*
X54370Y180718D03*
X68400Y193400D03*
X55800Y226100D03*
X35200Y207400D03*
X76100Y197000D03*
X38850Y222450D03*
X63206Y226229D03*
X40400Y192100D03*
X71850Y216100D03*
X76500Y202400D03*
X59800Y193700D03*
X29650Y235500D03*
X46200Y226200D03*
X51200Y226100D03*
X38814Y180206D03*
X33691Y179468D03*
X69399Y281699D03*
X69500Y276700D03*
X69400Y287100D03*
X35600Y292500D03*
Y287000D03*
Y280800D03*
X56500Y239800D03*
X41450Y256479D03*
X35500Y319100D03*
Y314000D03*
X35918Y307565D03*
X69304Y309100D03*
X69400Y303900D03*
X69200Y314100D03*
X57325Y337545D03*
X62325Y337845D03*
X36325Y337745D03*
X41325Y338045D03*
X43600Y362649D03*
X72446Y364233D03*
X29706Y364053D03*
X72356Y383400D03*
X50486Y364064D03*
X65300Y363049D03*
X22600Y362849D03*
X28200Y382900D03*
X30400Y397100D03*
X64700Y399000D03*
X42076Y383750D03*
X112997Y117234D03*
X112100Y124500D03*
X119700Y124600D03*
X93000Y147000D03*
X84800Y147100D03*
X100900Y147000D03*
X109100Y147100D03*
X116264Y136064D03*
X119700Y147200D03*
X133800Y165900D03*
X77600Y210700D03*
X79050Y217150D03*
X78805Y337855D03*
X84025Y338245D03*
X100270Y337248D03*
X105480Y338030D03*
X79292Y380900D03*
X93641Y364266D03*
X86395Y362842D03*
X99912Y412200D03*
X98614Y391150D03*
X84536Y390405D03*
Y395405D03*
X170050Y109625D03*
X165097Y139545D03*
X164810Y151500D03*
X190424Y122651D03*
X176500Y161200D03*
X184700Y159000D03*
X165319Y134201D03*
X162500Y128600D03*
X176083Y118985D03*
X190461Y128067D03*
X183498Y151582D03*
X183760Y118548D03*
X151697Y131670D03*
X164900Y123300D03*
X143655Y174344D03*
X181489Y208606D03*
X177550Y180450D03*
X153855Y184292D03*
X162523Y183631D03*
X171411Y184292D03*
X194000Y288000D03*
X198700Y289500D03*
X183901Y274213D03*
X259609Y52025D03*
X253613Y61140D03*
X231753Y60341D03*
X236750Y83000D03*
X223544Y74403D03*
X242733Y74428D03*
X250500Y95000D03*
X214350Y81543D03*
X258750Y85000D03*
X223650Y131900D03*
X255993Y130718D03*
X232300Y292200D03*
X251800Y292300D03*
X261600D03*
X246800Y292400D03*
X239700Y292600D03*
X227200Y292300D03*
X220900Y292500D03*
X240000Y298200D03*
X258800Y296500D03*
X221800Y298800D03*
X211300Y292302D03*
X216068Y260413D03*
X204368Y258164D03*
X228668Y262713D03*
X259690Y320875D03*
X245943Y322043D03*
X242091Y327293D03*
X227500Y318900D03*
X226500Y327500D03*
X214200Y324200D03*
X208960Y318800D03*
X221747Y384384D03*
X226200Y400600D03*
X230300Y407700D03*
X235300Y405400D03*
X248204Y372309D03*
X243664Y368975D03*
X243400Y378645D03*
X262672Y460813D03*
X283223Y29000D03*
X283173Y38000D03*
X287963Y33500D03*
X286848Y42500D03*
X296092Y93239D03*
X289398Y96815D03*
X322470Y111347D03*
X300168Y97933D03*
X306595Y98693D03*
X306196Y106297D03*
X311293Y109977D03*
X315932Y104519D03*
X294644Y60800D03*
X294822Y66022D03*
X279615Y88546D03*
X294914Y71626D03*
X271864Y82126D03*
X323484Y105921D03*
X289793Y85901D03*
X268962Y88452D03*
X291970Y76090D03*
X279804Y175047D03*
X292500Y125500D03*
X307369Y115952D03*
X302500Y115000D03*
X301400Y190000D03*
X281000Y218500D03*
X300943Y235180D03*
X273200Y219700D03*
X320628Y238548D03*
X325611Y296231D03*
X313650Y298850D03*
X274376Y250699D03*
X271800Y292600D03*
X266600Y292300D03*
X289817Y283261D03*
X297038Y285956D03*
X282362Y292400D03*
X280087Y283473D03*
X289056Y296534D03*
X316847Y243024D03*
X271468Y272013D03*
X267668Y267313D03*
X291268Y265113D03*
X285268Y269713D03*
X323950Y255200D03*
X265365Y320651D03*
X299791Y352123D03*
X285400Y326792D03*
X299100Y324500D03*
X294950Y317400D03*
X277250Y317700D03*
X279719Y383549D03*
X275782Y388274D03*
X280549Y391744D03*
X269500Y409600D03*
X275500Y413800D03*
X269954Y402990D03*
X283050Y413600D03*
X269977Y373425D03*
X266111Y379351D03*
X326632Y122343D03*
X327500Y134028D03*
X359000Y135000D03*
X377000Y289500D03*
X379257Y298785D03*
X377500Y283900D03*
Y277500D03*
X371437Y293000D03*
X361800Y245800D03*
X355700Y242500D03*
X350303Y238898D03*
X344600Y248800D03*
X374513Y265662D03*
X333054Y256852D03*
X356500Y266300D03*
X338054Y256852D03*
X334735Y303062D03*
X378500Y306500D03*
X350750Y343000D03*
X348900Y319600D03*
X350298Y333944D03*
X357895Y309272D03*
X351341Y313694D03*
X364596Y325590D03*
X366042Y318443D03*
X333794Y405044D03*
X326083Y416366D03*
X330531Y416439D03*
X332485Y435750D03*
X434083Y148279D03*
X444866Y152736D03*
X448416Y162119D03*
X430409Y335154D03*
X416841Y335528D03*
X395603Y345150D03*
X407304Y343726D03*
X430464Y351272D03*
X471096Y110797D03*
X479435Y105501D03*
X482779Y114109D03*
X470537Y105272D03*
X479830Y120100D03*
X477011Y126263D03*
X494472Y123575D03*
X490923Y130166D03*
X487008Y137123D03*
X464994Y146129D03*
X457326Y150586D03*
X472891Y154886D03*
X465088Y157094D03*
X456471Y159418D03*
X459221Y355189D03*
X510200Y359400D03*
X502450Y361450D03*
X494517Y335499D03*
X499517Y335504D03*
X509645Y335582D03*
X504581Y335524D03*
X491474Y342209D03*
X488444Y338409D03*
X486281Y346317D03*
X483500Y336000D03*
X472724Y335567D03*
X517097Y338315D03*
X518984Y419591D03*
X552200Y399200D03*
X542300Y399400D03*
X548400Y423600D03*
X566182Y423300D03*
X564415Y380334D03*
X566103Y386434D03*
X559514Y384907D03*
X569152Y378908D03*
X561746Y480600D03*
X551550Y480550D03*
X633000Y18000D03*
X632343Y55642D03*
X630888Y284129D03*
X625250Y284066D03*
X602273Y288661D03*
X614273D03*
X608273D03*
X629250Y332319D03*
X597250Y342400D03*
X606225Y356075D03*
X605900Y350800D03*
X610982Y348239D03*
X616800Y348100D03*
X608607Y326656D03*
X612907Y321774D03*
X624108Y322850D03*
X596631Y330137D03*
X608157Y310168D03*
X615900Y309900D03*
X612300Y378500D03*
Y373500D03*
X616600Y394600D03*
X592475Y382413D03*
X605070Y378970D03*
X592513Y376121D03*
X605600Y373500D03*
X622109Y385304D03*
Y364424D03*
X590400Y421200D03*
X625187Y378210D03*
X629602Y375862D03*
X599500Y480000D03*
X624898Y486518D03*
X613000Y484000D03*
X590640Y472600D03*
X600600Y430701D03*
X597140Y473590D03*
X582855Y476795D03*
X595500Y439400D03*
X627718Y473130D03*
X621500Y468000D03*
X633100Y449500D03*
X607500Y487500D03*
X581500Y489700D03*
X660500Y24600D03*
X657000Y46500D03*
X657440Y31815D03*
X660692Y42436D03*
X643103Y17648D03*
X638103Y16800D03*
X665012Y65659D03*
X645078Y61949D03*
X642000Y57500D03*
X636943Y57942D03*
X695151Y255091D03*
X689680Y261152D03*
X689764Y255264D03*
X683390Y302820D03*
X637500Y353500D03*
X652708Y378812D03*
X682000Y372160D03*
X655643Y389328D03*
X683563Y387733D03*
X695700Y385740D03*
X689800Y400850D03*
X663667Y395700D03*
X684100Y382050D03*
X678970Y400560D03*
X681800Y366200D03*
X663706Y423000D03*
X680560Y407500D03*
X661650Y390100D03*
X680000Y473500D03*
X677882Y449120D03*
X690000Y437000D03*
X695980Y432800D03*
X690690Y424820D03*
X742523Y100815D03*
X727727Y94148D03*
X719365Y96773D03*
X745700Y149600D03*
X747350Y165050D03*
X744552Y170076D03*
X744300Y160815D03*
X753050Y138650D03*
X749680Y169550D03*
X745351Y144396D03*
X752700Y143850D03*
X748000Y138330D03*
X712720Y229666D03*
X757337Y271913D03*
X760000Y290500D03*
X757483Y305724D03*
Y310924D03*
X716500Y376500D03*
X708337Y390944D03*
X716000Y393000D03*
X721100Y387500D03*
X735943Y475465D03*
X710268Y446055D03*
X700900Y441785D03*
X729837Y428237D03*
X736130Y451570D03*
X714400Y442500D03*
X743160Y428240D03*
X724340Y443410D03*
X784767Y84511D03*
X765615Y157200D03*
X762350Y186150D03*
X770351Y176500D03*
X783390Y286000D03*
X779890Y289000D03*
X767532Y289746D03*
X763840Y271430D03*
X776518Y246482D03*
X767663Y250993D03*
X763505Y316008D03*
X789597Y306335D03*
X789658Y301111D03*
X791520Y327000D03*
G54D40*
X44850Y202810D03*
Y216590D03*
X64950D03*
Y202810D03*
G54D115*
X674843Y382515D03*
X672874D03*
X663032D03*
X661063D03*
X665000D03*
X666969D03*
X668937D03*
X670906D03*
G54D106*
X604400Y456100D03*
G54D22*
X52607Y168352D03*
X56607D03*
X72800Y183200D03*
X25900Y203600D03*
X65500Y231100D03*
X45938Y232004D03*
X41938D03*
X64100Y184400D03*
X46500Y183500D03*
X50500D03*
X26600Y275500D03*
X27200Y301800D03*
X65500Y372100D03*
X22000Y371652D03*
X43000Y371533D03*
X73100Y372100D03*
X29900Y371652D03*
X50700Y371533D03*
X87300Y223700D03*
X89800Y183400D03*
X85795Y371726D03*
X93695D03*
X89600Y391200D03*
X195161Y128117D03*
X201139Y114695D03*
X156700Y132800D03*
X250791Y65727D03*
X238880Y66862D03*
X220227Y66815D03*
X238900Y284500D03*
X245800Y284600D03*
X219400Y284000D03*
X226600Y284500D03*
X260000D03*
X240200Y303400D03*
X258700Y300900D03*
X222000Y303300D03*
X255500Y415800D03*
X318050Y293200D03*
X267600Y284500D03*
X285400Y317400D03*
X283000Y405800D03*
X269500Y416800D03*
X343000Y302300D03*
X345121Y328050D03*
X370932Y320300D03*
X326083Y409166D03*
X412400Y340384D03*
X437500Y340800D03*
X427700Y340600D03*
X400300Y341700D03*
X469996Y351012D03*
X451400Y340800D03*
X460327Y340801D03*
X464327D03*
X482427Y354974D03*
X486627D03*
X497900Y341900D03*
X502700D03*
X507337Y341863D03*
X478298Y354854D03*
X480700Y340800D03*
X522000Y351450D03*
X512754Y341784D03*
X573570Y460280D03*
X590350Y327050D03*
X618900Y319400D03*
X631800Y319300D03*
X629370Y456630D03*
X586720Y472980D03*
X664301Y31865D03*
X664000Y53800D03*
X643492Y86736D03*
X639392D03*
X682700Y233800D03*
X695600D03*
X695100Y378300D03*
X675831Y392633D03*
X670610Y415430D03*
X675380Y454460D03*
X667900Y443200D03*
X755523Y90115D03*
X751023D03*
X699600Y233800D03*
X743600Y221000D03*
X739500D03*
X734286Y221023D03*
X726656Y228498D03*
X719300Y217500D03*
X759651Y263407D03*
X751470Y307320D03*
X700200Y378300D03*
X763840Y263310D03*
X782800Y324770D03*
G54D13*
X53100Y152000D03*
X27000Y292200D03*
Y287700D03*
X61867Y242333D03*
X41500Y266100D03*
X27300Y318500D03*
Y314000D03*
X57400Y403150D03*
X85600Y194900D03*
X84100Y213800D03*
X160100Y113400D03*
X156600Y122000D03*
X160100Y117700D03*
X255300Y90000D03*
Y95000D03*
X207800Y284000D03*
X296435Y104177D03*
X277300Y321600D03*
X270668Y378200D03*
Y382200D03*
X274769Y373425D03*
X369300Y279500D03*
X362800Y293000D03*
X369300Y275500D03*
X369100Y283900D03*
X349800Y308000D03*
X358300Y340500D03*
X370800Y344500D03*
X361327Y312654D03*
X370982Y328503D03*
X340550Y309823D03*
X326638Y405044D03*
X388949Y340563D03*
X470397Y358638D03*
X527915Y335679D03*
Y331679D03*
X635992Y94236D03*
X629300Y278745D03*
X593800Y346950D03*
X597723Y352729D03*
Y356729D03*
X600587Y322456D03*
Y326656D03*
X622350Y348900D03*
X619850Y353400D03*
X622350Y310491D03*
X619850Y314991D03*
X611850D03*
X612350Y353400D03*
X597373Y378955D03*
Y374955D03*
X617067Y378894D03*
Y374894D03*
X586600Y486650D03*
X581000Y460300D03*
X581070Y468530D03*
X643492Y94236D03*
X668231Y392433D03*
X672800Y407500D03*
X646020Y395300D03*
X743500Y94500D03*
X728531Y98293D03*
X736000Y86200D03*
Y90300D03*
X743500Y86300D03*
Y90400D03*
X757471Y143624D03*
X757450Y139500D03*
X753600Y169550D03*
X758500Y135400D03*
X750408Y154100D03*
X750400Y160050D03*
X750423Y148245D03*
X753602Y173715D03*
X751268Y164081D03*
X753618Y179053D03*
X753630Y197200D03*
X711800Y217500D03*
X753618Y183153D03*
Y187253D03*
X753630Y206200D03*
X747270Y297120D03*
X754183Y317184D03*
X725270Y423930D03*
X728200Y475400D03*
X794770Y307120D03*
Y302620D03*
G54D31*
X38502Y161319D03*
X49302D03*
X43902D03*
X49302Y150519D03*
Y155919D03*
X43902Y150519D03*
Y155919D03*
X38502D03*
Y150519D03*
X108672Y138471D03*
Y132871D03*
X90672Y138471D03*
X102672D03*
X96672D03*
X84672D03*
Y132871D03*
X96672D03*
X102672D03*
X90672D03*
G54D50*
X69300Y372000D03*
X26100Y371552D03*
X46900Y371433D03*
X89895Y371626D03*
X164810Y143631D03*
X189413Y114544D03*
X279000Y405700D03*
X348597Y217040D03*
X337900Y424200D03*
X598152Y362741D03*
X598023Y386411D03*
X690500Y382000D03*
X683781Y392333D03*
X701120Y433820D03*
X797155Y293467D03*
X805300Y267200D03*
G54D32*
X56541Y231086D03*
X75500Y231100D03*
X33700Y223500D03*
X76800Y183200D03*
X29900Y203600D03*
X70500Y231100D03*
X52400D03*
X32405Y184317D03*
X36405D03*
X30700Y275500D03*
X31400Y301800D03*
X25700Y388500D03*
X77200Y367100D03*
X38200Y366900D03*
X34100D03*
X60400Y366700D03*
X54800D03*
X25700Y396000D03*
X37500Y384000D03*
X85700Y183400D03*
X91300Y223700D03*
X93700Y391200D03*
X81300Y367100D03*
X98295Y366893D03*
X102395D03*
X246530Y66836D03*
X252000Y284500D03*
X230700D03*
X256000D03*
X234800Y284400D03*
X215300Y284000D03*
X271600Y284500D03*
X275600D03*
X294708Y292126D03*
X287214Y288217D03*
X323900Y247800D03*
X265250Y370750D03*
X279000Y398300D03*
X348597Y209640D03*
X365387Y258009D03*
X372119Y257880D03*
X384000Y341050D03*
X330531Y409161D03*
X416841Y340384D03*
X447300Y340800D03*
X472296D03*
X506200Y352300D03*
X499700D03*
X493200D03*
X476500Y340800D03*
X532894Y347615D03*
X528894D03*
X535336Y331822D03*
X541714Y331803D03*
X547315Y331788D03*
X551394D03*
X518000Y351450D03*
X514000Y351600D03*
X613211Y280205D03*
X608711D03*
X617000Y472800D03*
X621500D03*
X667353Y226932D03*
X641579Y227190D03*
X658610Y226975D03*
X663110D03*
X654464Y227115D03*
X650287Y227074D03*
X645968Y227097D03*
X691100Y233800D03*
X686900D03*
X678500D03*
X654770Y394660D03*
X658840D03*
X687581Y392433D03*
X686390Y424870D03*
X695380Y424850D03*
X731900Y88600D03*
X730712Y228507D03*
X738786Y228523D03*
X725750Y217572D03*
X712720Y234422D03*
X746970Y307320D03*
X700200Y391300D03*
X710200Y434530D03*
X717150Y450295D03*
X706120Y434530D03*
X743480Y432190D03*
X801934Y287746D03*
G54D116*
X694512Y457271D03*
G54D23*
X49200Y142500D03*
X44200D03*
X39200D03*
X34200D03*
G54D107*
X614043Y465943D03*
Y463974D03*
Y462006D03*
Y460037D03*
Y458069D03*
Y456100D03*
Y454131D03*
Y452163D03*
Y450194D03*
Y448226D03*
Y446257D03*
X594757D03*
Y448226D03*
Y450194D03*
Y452163D03*
Y454131D03*
Y456100D03*
Y458069D03*
Y460037D03*
Y462006D03*
Y463974D03*
Y465943D03*
G54D41*
X45150Y204779D03*
Y206747D03*
Y208716D03*
Y210684D03*
Y212653D03*
Y214621D03*
X64650D03*
Y212653D03*
Y210684D03*
Y208716D03*
Y206747D03*
Y204779D03*
G54D14*
X56500Y152000D03*
X30400Y292200D03*
Y287700D03*
X65267Y242333D03*
X44900Y266100D03*
X30700Y318500D03*
Y314000D03*
X60800Y403150D03*
X89000Y194900D03*
X87500Y213800D03*
X163500Y113400D03*
X160000Y122000D03*
X163500Y117700D03*
X258700Y90000D03*
Y95000D03*
X211200Y284000D03*
X299835Y104177D03*
X280700Y321600D03*
X274068Y378200D03*
Y382200D03*
X278169Y373425D03*
X372700Y279500D03*
X366200Y293000D03*
X372700Y275500D03*
X372500Y283900D03*
X353200Y308000D03*
X361700Y340500D03*
X374200Y344500D03*
X364727Y312654D03*
X374382Y328503D03*
X343950Y309823D03*
X330038Y405044D03*
X392349Y340563D03*
X473797Y358638D03*
X531315Y335679D03*
Y331679D03*
X632700Y278745D03*
X597200Y346950D03*
X601123Y352729D03*
Y356729D03*
X603987Y322456D03*
Y326656D03*
X625750Y348900D03*
X623250Y353400D03*
X625750Y310491D03*
X623250Y314991D03*
X615250D03*
X615750Y353400D03*
X600773Y378955D03*
Y374955D03*
X620467Y378894D03*
Y374894D03*
X590000Y486650D03*
X584400Y460300D03*
X584470Y468530D03*
X646892Y94236D03*
X639392D03*
X671631Y392433D03*
X676200Y407500D03*
X649420Y395300D03*
X746900Y94500D03*
X731931Y98293D03*
X739400Y86200D03*
Y90300D03*
X746900Y86300D03*
Y90400D03*
X757000Y169550D03*
X753808Y154100D03*
X753800Y160050D03*
X753823Y148245D03*
X757002Y173715D03*
X754668Y164081D03*
X757018Y179053D03*
X757030Y197200D03*
X715200Y217500D03*
X757018Y183153D03*
Y187253D03*
X757030Y206200D03*
X750670Y297120D03*
X757583Y317184D03*
X728670Y423930D03*
X731600Y475400D03*
X760871Y143624D03*
X760850Y139500D03*
X761900Y135400D03*
X798170Y307120D03*
Y302620D03*
G54D33*
X56541Y234486D03*
X75500Y234500D03*
X33700Y226900D03*
X76800Y186600D03*
X29900Y207000D03*
X70500Y234500D03*
X52400D03*
X32405Y187717D03*
X36405D03*
X30700Y278900D03*
X31400Y305200D03*
X25700Y391900D03*
X77200Y370500D03*
X38200Y370300D03*
X34100D03*
X60400Y370100D03*
X54800D03*
X25700Y399400D03*
X37500Y387400D03*
X85700Y186800D03*
X91300Y227100D03*
X93700Y394600D03*
X81300Y370500D03*
X98295Y370293D03*
X102395D03*
X246530Y70236D03*
X252000Y287900D03*
X230700D03*
X256000D03*
X234800Y287800D03*
X215300Y287400D03*
X271600Y287900D03*
X275600D03*
X294708Y295526D03*
X287214Y291617D03*
X323900Y251200D03*
X265250Y374150D03*
X279000Y401700D03*
X348597Y213040D03*
X365387Y261409D03*
X372119Y261280D03*
X384000Y344450D03*
X330531Y412561D03*
X416841Y343784D03*
X447300Y344200D03*
X472296D03*
X506200Y355700D03*
X499700D03*
X493200D03*
X476500Y344200D03*
X532894Y351015D03*
X528894D03*
X535336Y335222D03*
X541714Y335203D03*
X547315Y335188D03*
X551394D03*
X518000Y354850D03*
X514000Y355000D03*
X613211Y283605D03*
X608711D03*
X617000Y476200D03*
X621500D03*
X667353Y230332D03*
X641579Y230590D03*
X658610Y230375D03*
X663110D03*
X654464Y230515D03*
X650287Y230474D03*
X645968Y230497D03*
X691100Y237200D03*
X686900D03*
X678500D03*
X654770Y398060D03*
X658840D03*
X687581Y395833D03*
X686390Y428270D03*
X695380Y428250D03*
X731900Y92000D03*
X730712Y231907D03*
X738786Y231923D03*
X725750Y220972D03*
X712720Y237822D03*
X746970Y310720D03*
X700200Y394700D03*
X710200Y437930D03*
X717150Y453695D03*
X706120Y437930D03*
X743480Y435590D03*
X801934Y291146D03*
G54D15*
X31000Y165500D03*
X29600Y227500D03*
Y223500D03*
X30400Y283200D03*
Y296700D03*
X44900Y261900D03*
X30700Y323000D03*
Y309500D03*
X77200Y314000D03*
X68750Y367751D03*
X26050Y367552D03*
X47100Y367400D03*
X87500Y217900D03*
X89000Y190900D03*
X77496Y281695D03*
Y276695D03*
Y286695D03*
X77400Y309500D03*
Y304500D03*
X89845Y367626D03*
X163970Y104310D03*
X187000Y110000D03*
X179500D03*
X163500Y109050D03*
X173500Y114500D03*
X196813Y114644D03*
X233700Y68000D03*
X231200Y73000D03*
X203700Y298800D03*
Y306800D03*
X257891Y371827D03*
X263200Y412100D03*
Y420300D03*
X259450Y426500D03*
X277700Y42500D03*
Y38000D03*
Y33500D03*
Y29000D03*
X286941Y278576D03*
X301410Y281122D03*
X281906Y297434D03*
X294900Y321700D03*
X372500Y288000D03*
X366200Y299200D03*
X374200D03*
Y340500D03*
X366200Y303200D03*
X374200D03*
X345091Y319717D03*
X345100Y323900D03*
X332386Y443510D03*
X433914Y356373D03*
X481700Y362400D03*
X477600Y350800D03*
X481700Y366800D03*
X625700Y162500D03*
X600737Y280017D03*
X625200Y278745D03*
X630528Y364424D03*
Y385304D03*
X601040Y395220D03*
X612350D03*
X629770Y468430D03*
X629323Y477831D03*
X594400Y479100D03*
X595390Y430440D03*
X668381Y400183D03*
X685800Y440950D03*
X686700Y433300D03*
X754400Y97800D03*
X757030Y201700D03*
Y214200D03*
Y210200D03*
X757583Y321684D03*
X750670Y301620D03*
X735442Y447367D03*
X727790Y447430D03*
X718050Y446230D03*
X766000Y164200D03*
X775436Y293180D03*
X783340D03*
G54D51*
X69300Y375600D03*
X26100Y375152D03*
X46900Y375033D03*
X89895Y375226D03*
X164810Y147231D03*
X189413Y118144D03*
X279000Y409300D03*
X348597Y220640D03*
X337900Y427800D03*
X598152Y366341D03*
X598023Y390011D03*
X690500Y385600D03*
X683781Y395933D03*
X701120Y437420D03*
X797155Y297067D03*
X805300Y270800D03*
G54D24*
X76600Y134220D03*
Y120380D03*
G54D42*
X54900Y209700D03*
G54D117*
X684769Y452153D03*
Y454712D03*
Y457271D03*
Y459830D03*
Y462389D03*
X704255D03*
Y459830D03*
Y457271D03*
Y454712D03*
Y452153D03*
G54D108*
X649606Y111811D03*
X646456D03*
X649606Y114960D03*
X646456D03*
X643307D03*
X649606Y118110D03*
X646456D03*
X643307D03*
X649606Y196850D03*
X646456D03*
X643307D03*
X649606Y200000D03*
X646456D03*
X643307D03*
X649606Y203149D03*
X646456D03*
X731496Y111811D03*
X728346D03*
X734645Y114960D03*
X731496D03*
X728346D03*
X734645Y118110D03*
X731496D03*
X728346D03*
X734645Y196850D03*
X731496D03*
X728346D03*
X734645Y200000D03*
X731496D03*
X728346D03*
X731496Y203149D03*
X728346D03*
G54D60*
X98425Y472441D03*
X137795D03*
G54D16*
X27600Y165500D03*
X26200Y227500D03*
Y223500D03*
X74096Y281695D03*
Y276695D03*
Y286695D03*
X27000Y283200D03*
Y296700D03*
X41500Y261900D03*
X27300Y323000D03*
Y309500D03*
X73800Y314000D03*
X74000Y309500D03*
Y304500D03*
X65350Y367751D03*
X22650Y367552D03*
X43700Y367400D03*
X84100Y217900D03*
X85600Y190900D03*
X86445Y367626D03*
X160570Y104310D03*
X183600Y110000D03*
X176100D03*
X160100Y109050D03*
X170100Y114500D03*
X193413Y114644D03*
X200300Y298800D03*
Y306800D03*
X230300Y68000D03*
X227800Y73000D03*
X254491Y371827D03*
X259800Y412100D03*
Y420300D03*
X256050Y426500D03*
X274300Y42500D03*
Y38000D03*
Y33500D03*
Y29000D03*
X283541Y278576D03*
X298010Y281122D03*
X278506Y297434D03*
X291500Y321700D03*
X369100Y288000D03*
X362800Y299200D03*
X370800D03*
Y340500D03*
X362800Y303200D03*
X370800D03*
X341691Y319717D03*
X341700Y323900D03*
X328986Y443510D03*
X430514Y356373D03*
X478300Y362400D03*
X474200Y350800D03*
X478300Y366800D03*
X622300Y162500D03*
X597337Y280017D03*
X621800Y278745D03*
X627128Y364424D03*
Y385304D03*
X597640Y395220D03*
X608950D03*
X626370Y468430D03*
X625923Y477831D03*
X591000Y479100D03*
X591990Y430440D03*
X664981Y400183D03*
X682400Y440950D03*
X683300Y433300D03*
X751000Y97800D03*
X753630Y201700D03*
Y214200D03*
Y210200D03*
X754183Y321684D03*
X747270Y301620D03*
X732042Y447367D03*
X724390Y447430D03*
X714650Y446230D03*
X762600Y164200D03*
X772036Y293180D03*
X779940D03*
G54D52*
X46277Y517441D03*
G54D25*
X33000Y159300D03*
Y151700D03*
X89433Y125588D03*
Y117988D03*
X104930Y125610D03*
Y118010D03*
X97230Y125620D03*
Y118020D03*
X153300Y174700D03*
Y167100D03*
X161300Y174700D03*
Y167100D03*
X169300Y174700D03*
Y167100D03*
X141200Y192000D03*
Y199600D03*
X148900Y192000D03*
Y199600D03*
X156700Y192000D03*
Y199600D03*
X172300Y192000D03*
Y199600D03*
X164400Y192000D03*
Y199600D03*
X210500Y206400D03*
Y198800D03*
X243300Y354900D03*
Y362500D03*
X239125Y481261D03*
X231125D03*
X247125D03*
X239125Y488861D03*
X231125D03*
X247125D03*
X560000Y392200D03*
Y399800D03*
X545206Y416682D03*
Y409082D03*
X553206Y416682D03*
Y409082D03*
X561706Y416682D03*
Y409082D03*
X626900Y441200D03*
Y433600D03*
X606000Y438800D03*
Y431200D03*
X635000Y433700D03*
Y441300D03*
X688200Y321700D03*
Y329300D03*
X696305Y329202D03*
Y321602D03*
X667617Y352167D03*
Y359767D03*
X646600Y372200D03*
Y364600D03*
X704805Y329202D03*
Y321602D03*
G54D109*
X684800Y313200D03*
X695800D03*
X720383Y412014D03*
X709383D03*
X720383Y403014D03*
X709383D03*
G54D70*
X180753Y137606D03*
X178784D03*
X176816D03*
X174847D03*
Y125394D03*
X176816D03*
X178784D03*
X180753D03*
G54D118*
X697071Y447528D03*
X694512D03*
X691953D03*
X689394D03*
Y467014D03*
X691953D03*
X694512D03*
X697071D03*
X699630Y447528D03*
Y467014D03*
G54D34*
X68400Y182100D03*
X81300Y182200D03*
X169800Y144200D03*
X208100Y162100D03*
X296500Y138700D03*
X297000Y222550D03*
X296500Y180500D03*
X283100Y418600D03*
X566500Y392700D03*
X624770Y455430D03*
X615870Y433930D03*
X620600Y433900D03*
X681900Y321800D03*
X681540Y419660D03*
X686300Y365500D03*
X672800Y442600D03*
G54D61*
X94488Y464075D03*
X102362D03*
X110236D03*
X118110D03*
X125984D03*
X133858D03*
X94488Y480807D03*
X102362D03*
X110236D03*
X118110D03*
X125984D03*
X133858D03*
X141732Y464075D03*
Y480807D03*
G54D43*
X54900Y204700D03*
X49900Y209700D03*
X59900D03*
X54900Y214700D03*
Y209700D03*
X201400Y174400D03*
X192400D03*
X196900D03*
X179800Y133500D03*
X175800Y129500D03*
X179800D03*
X175800Y133500D03*
X192400Y191600D03*
X196900D03*
X201400D03*
X192400Y187300D03*
X196900D03*
X201400D03*
Y178700D03*
X192400Y183000D03*
X196900D03*
X201400D03*
X192400Y178700D03*
X196900D03*
X246493Y399567D03*
X242893D03*
X257020Y390670D03*
X253420D03*
X249820D03*
X246220D03*
X256120Y395170D03*
X243120D03*
X247620D03*
X251870D03*
X242620Y390670D03*
X260893Y399567D03*
X257293D03*
X260620Y390670D03*
Y395170D03*
X253693Y399567D03*
X250093D03*
X609400Y446850D03*
X604400Y456100D03*
Y451850D03*
Y447350D03*
Y460350D03*
X609400Y450450D03*
Y454050D03*
Y457650D03*
Y461250D03*
X599503Y447123D03*
Y450723D03*
Y454323D03*
Y457923D03*
X604400Y464850D03*
X609400D03*
X599503Y461523D03*
Y465123D03*
X694400Y452900D03*
Y457400D03*
Y461900D03*
X689900Y457400D03*
Y452950D03*
X689700Y461850D03*
X698900Y457400D03*
X699000Y452950D03*
X698950Y461800D03*
G54D17*
X56507Y175552D03*
X75400Y221000D03*
X34900Y211900D03*
X36249Y191548D03*
X50300Y190700D03*
X75400Y321700D03*
X74200Y338000D03*
X31500Y337800D03*
X52500Y337600D03*
X60900Y391050D03*
X60880Y399390D03*
X95295Y337793D03*
X181100Y114500D03*
X197013Y118544D03*
X204694Y209985D03*
X252645Y279732D03*
X211200Y287800D03*
X221800Y484000D03*
X279126Y278333D03*
X280700Y328400D03*
X354300Y347500D03*
X332508Y439668D03*
X539300Y418400D03*
X621800Y166500D03*
X600837Y284017D03*
X625300Y288745D03*
X597300Y334350D03*
X625300Y327654D03*
X597300Y337900D03*
X595470Y426720D03*
X590100Y490400D03*
X669083Y347018D03*
X671767Y396181D03*
X753908Y280164D03*
X731700Y463900D03*
X739120Y427980D03*
G54D119*
X735512Y410241D03*
Y377189D03*
G54D26*
X33100Y171500D03*
X25500D03*
X34100Y217500D03*
X26500D03*
X63626Y250139D03*
X56026D03*
X183498Y145380D03*
X191098D03*
X236000Y362400D03*
X228400D03*
X236000Y370100D03*
X228400D03*
X236000Y377800D03*
X228400D03*
X234300Y394954D03*
X226700D03*
X223800Y478500D03*
X216200D03*
X223800Y470500D03*
X216200D03*
X281300Y147500D03*
X273700D03*
X281300Y156500D03*
X273700D03*
X281300Y239500D03*
X273700D03*
X281300Y198000D03*
X273700D03*
X281300Y231000D03*
X273700D03*
X281300Y189500D03*
X273700D03*
X540800Y423900D03*
X533200D03*
X540800Y431500D03*
X533200D03*
X647600Y354400D03*
X655200D03*
X647600Y346700D03*
X655200D03*
X647600Y339000D03*
X655200D03*
X647623Y331307D03*
X655223D03*
X647623Y323624D03*
X655223D03*
X695100Y483400D03*
X712598Y459729D03*
X720198D03*
X733700Y469400D03*
X726100D03*
X712100Y467900D03*
X719700D03*
X712034Y475600D03*
X719634D03*
X712034Y483400D03*
X719634D03*
X702700D03*
G54D80*
X261713Y386027D03*
X259744D03*
X257776D03*
X255807D03*
X253839D03*
X251870D03*
X249901D03*
X247933D03*
X245964D03*
X243996D03*
X242027D03*
Y405313D03*
X243996D03*
X245964D03*
X247933D03*
X249901D03*
X251870D03*
X253839D03*
X255807D03*
X257776D03*
X259744D03*
X261713D03*
G54D35*
X68400Y187700D03*
X81300Y187800D03*
X169800Y149800D03*
X208100Y167700D03*
X296500Y144300D03*
X297000Y228150D03*
X296500Y186100D03*
X283100Y424200D03*
X566500Y398300D03*
X624770Y461030D03*
X615870Y439530D03*
X620600Y439500D03*
X681900Y327400D03*
X686300Y371100D03*
X672800Y448200D03*
X681540Y425260D03*
G54D44*
X74100Y291700D03*
X71800Y318200D03*
X46700Y387500D03*
X95850Y452650D03*
X222200Y95000D03*
X241700D03*
X239000Y279700D03*
X231800Y316900D03*
X250175Y316967D03*
X214400Y317000D03*
X269565Y317151D03*
X291300Y328300D03*
X356500Y334000D03*
X626200Y166500D03*
X629200Y299091D03*
Y288745D03*
Y337500D03*
Y327654D03*
X622770Y369320D03*
X623470Y389940D03*
X586550Y482900D03*
X595700Y434500D03*
X689935Y441196D03*
X714100Y489400D03*
G54D71*
X177800Y131500D03*
G54D53*
X37402Y499724D03*
X789370D03*
G54D62*
X158267Y25708D03*
X145669D03*
X158267Y47362D03*
X145669D03*
G54D36*
X59800Y188700D03*
X82600Y228300D03*
X176500Y175400D03*
X178500Y198800D03*
X297000Y164800D03*
X296500Y205900D03*
Y247950D03*
X569070Y466030D03*
X581000Y398300D03*
X695700Y395850D03*
X647623Y384089D03*
X642907D03*
X715800Y387400D03*
X736400Y462200D03*
G54D18*
X52907Y175552D03*
X71800Y221000D03*
X31300Y211900D03*
X32649Y191548D03*
X46700Y190700D03*
X71800Y321700D03*
X70600Y338000D03*
X27900Y337800D03*
X48900Y337600D03*
X57300Y391050D03*
X57280Y399390D03*
X91695Y337793D03*
X177500Y114500D03*
X193413Y118544D03*
X201094Y209985D03*
X249045Y279732D03*
X207600Y287800D03*
X218200Y484000D03*
X275526Y278333D03*
X277100Y328400D03*
X350700Y347500D03*
X328908Y439668D03*
X535700Y418400D03*
X618200Y166500D03*
X597237Y284017D03*
X621700Y288745D03*
X593700Y334350D03*
X621700Y327654D03*
X593700Y337900D03*
X591870Y426720D03*
X586500Y490400D03*
X665483Y347018D03*
X668167Y396181D03*
X750308Y280164D03*
X728100Y463900D03*
X735520Y427980D03*
G54D27*
X43487Y166781D03*
X39612Y174281D03*
X47362D03*
X656500Y63250D03*
X660375Y70750D03*
X652625D03*
G54D90*
X340250Y292980D03*
X332750Y296855D03*
Y289105D03*
G54D72*
X185789Y188000D03*
G54D81*
X236820Y417395D03*
Y439281D03*
G54D54*
X37402Y535158D03*
X789370D03*
G54D45*
X28150Y265800D03*
X35650Y261925D03*
Y269675D03*
G54D63*
X158267Y53267D03*
Y41456D03*
Y31614D03*
Y19803D03*
X145669D03*
Y31614D03*
Y41456D03*
Y53267D03*
G54D64*
X149100Y136500D03*
X152700D03*
G54D73*
X223549Y81399D03*
X226109D03*
X228669D03*
Y87899D03*
X223549D03*
X243049Y81399D03*
X245609D03*
X248169D03*
Y87899D03*
X243049D03*
X292378Y304389D03*
X294938D03*
X297498D03*
Y310889D03*
X292378D03*
X279378Y304389D03*
X281938D03*
X284498D03*
Y310889D03*
X279378D03*
X327365Y422661D03*
X332485D03*
Y429161D03*
X329925D03*
X327365D03*
X670494Y425456D03*
X675614D03*
Y431956D03*
X673054D03*
X670494D03*
G54D46*
X62500Y292200D03*
Y287200D03*
Y282200D03*
Y277200D03*
X42500D03*
Y282200D03*
Y287200D03*
Y292200D03*
X62404Y319922D03*
Y314922D03*
Y309922D03*
Y304922D03*
X42404D03*
Y309922D03*
Y314922D03*
Y319922D03*
G54D28*
X66403Y140952D03*
X59997D03*
G54D19*
X26500Y160300D03*
X49700Y398200D03*
X242733Y70311D03*
X223995Y70291D03*
X226200Y408200D03*
X275500Y409300D03*
X344891Y209640D03*
X691400Y394700D03*
X652200Y370100D03*
X757488Y301161D03*
X713150Y453795D03*
X778440Y282210D03*
X786560Y328230D03*
G54D55*
X116063Y14567D03*
G54D91*
X353556Y257143D03*
X353500Y262500D03*
X432200Y341500D03*
X421375Y346552D03*
X421357Y341201D03*
X465300Y351481D03*
X455900Y341100D03*
X493200Y347700D03*
X485500Y432820D03*
X490800D03*
X485500Y427520D03*
X490800D03*
Y443420D03*
X485500D03*
Y438120D03*
X490800D03*
X518020Y343632D03*
X523602Y345779D03*
X528902Y341725D03*
X678500Y227500D03*
X695600D03*
X686900D03*
X682700Y223300D03*
X691721D03*
X646318Y217778D03*
X671508Y220824D03*
X650684Y221630D03*
X654464Y217358D03*
X661452Y217241D03*
X664452Y222315D03*
X657920Y221560D03*
X641579Y221770D03*
X667166Y217194D03*
X675264Y216982D03*
X748500Y109750D03*
X754000Y109600D03*
X726039Y84955D03*
X759023Y97440D03*
X737100Y95600D03*
X760100Y130900D03*
X749200Y126250D03*
X755300Y131150D03*
X754000Y126250D03*
X760450Y119550D03*
X750400Y131050D03*
X701500Y219000D03*
X707000Y217500D03*
X748644Y191051D03*
X701500Y225500D03*
X760500Y126000D03*
X764900Y130800D03*
X765500Y119500D03*
X763500Y115000D03*
X765800Y125800D03*
X773000Y315800D03*
G54D82*
X276700Y66700D03*
X306292Y252825D03*
X302262Y262642D03*
X332000Y266336D03*
X337500Y266050D03*
X594200Y395200D03*
X604832Y395220D03*
X640144Y40969D03*
X696850Y111811D03*
X693700D03*
X690551D03*
X687401D03*
X684252D03*
X681102D03*
X677952D03*
X674803D03*
X671653D03*
X668504D03*
X665354D03*
X662204D03*
X659055D03*
X655905D03*
X652756D03*
X696850Y114960D03*
X693700D03*
X690551D03*
X687401D03*
X684252D03*
X681102D03*
X677952D03*
X674803D03*
X671653D03*
X668504D03*
X665354D03*
X662204D03*
X659055D03*
X655905D03*
X652756D03*
X696850Y118110D03*
X693700D03*
X690551D03*
X687401D03*
X684252D03*
X681102D03*
X677952D03*
X674803D03*
X671653D03*
X668504D03*
X665354D03*
X662204D03*
X659055D03*
X655905D03*
X652756D03*
X696850Y121260D03*
X693700D03*
X690551D03*
X687401D03*
X684252D03*
X681102D03*
X677952D03*
X674803D03*
X671653D03*
X668504D03*
X665354D03*
X662204D03*
X659055D03*
X655905D03*
X652756D03*
X649606D03*
X646456D03*
X643307D03*
X696850Y124409D03*
X693700D03*
X690551D03*
X687401D03*
X684252D03*
X681102D03*
X677952D03*
X674803D03*
X671653D03*
X668504D03*
X665354D03*
X662204D03*
X659055D03*
X655905D03*
X652756D03*
X649606D03*
X646456D03*
X643307D03*
X696850Y127559D03*
X693700D03*
X690551D03*
X687401D03*
X684252D03*
X681102D03*
X677952D03*
X674803D03*
X671653D03*
X668504D03*
X665354D03*
X662204D03*
X659055D03*
X655905D03*
X652756D03*
X649606D03*
X646456D03*
X643307D03*
X696850Y130708D03*
X693700D03*
X690551D03*
X687401D03*
X684252D03*
X681102D03*
X677952D03*
X674803D03*
X671653D03*
X668504D03*
X665354D03*
X662204D03*
X659055D03*
X655905D03*
X652756D03*
X649606D03*
X646456D03*
X643307D03*
X696850Y133858D03*
X693700D03*
X690551D03*
X687401D03*
X684252D03*
X681102D03*
X677952D03*
X674803D03*
X671653D03*
X668504D03*
X665354D03*
X662204D03*
X659055D03*
X655905D03*
X652756D03*
X649606D03*
X646456D03*
X643307D03*
X696850Y137008D03*
X693700D03*
X690551D03*
X687401D03*
X684252D03*
X681102D03*
X677952D03*
X674803D03*
X671653D03*
X668504D03*
X665354D03*
X662204D03*
X659055D03*
X655905D03*
X652756D03*
X649606D03*
X646456D03*
X643307D03*
X696850Y140157D03*
X693700D03*
X690551D03*
X687401D03*
X684252D03*
X681102D03*
X677952D03*
X674803D03*
X671653D03*
X668504D03*
X665354D03*
X662204D03*
X659055D03*
X655905D03*
X652756D03*
X649606D03*
X646456D03*
X643307D03*
X696850Y143307D03*
X693700D03*
X690551D03*
X687401D03*
X684252D03*
X681102D03*
X677952D03*
X674803D03*
X671653D03*
X668504D03*
X665354D03*
X662204D03*
X659055D03*
X655905D03*
X652756D03*
X649606D03*
X646456D03*
X643307D03*
X696850Y146456D03*
X693700D03*
X690551D03*
X687401D03*
X684252D03*
X681102D03*
X677952D03*
X674803D03*
X671653D03*
X668504D03*
X665354D03*
X662204D03*
X659055D03*
X655905D03*
X652756D03*
X649606D03*
X646456D03*
X643307D03*
X696850Y149606D03*
X693700D03*
X690551D03*
X687401D03*
X684252D03*
X681102D03*
X677952D03*
X674803D03*
X671653D03*
X668504D03*
X665354D03*
X662204D03*
X659055D03*
X655905D03*
X652756D03*
X649606D03*
X646456D03*
X643307D03*
X696850Y152756D03*
X693700D03*
X690551D03*
X687401D03*
X684252D03*
X681102D03*
X677952D03*
X674803D03*
X671653D03*
X668504D03*
X665354D03*
X662204D03*
X659055D03*
X655905D03*
X652756D03*
X649606D03*
X646456D03*
X643307D03*
X696850Y155905D03*
X693700D03*
X690551D03*
X687401D03*
X684252D03*
X681102D03*
X677952D03*
X674803D03*
X671653D03*
X668504D03*
X665354D03*
X662204D03*
X659055D03*
X655905D03*
X652756D03*
X649606D03*
X646456D03*
X643307D03*
X696850Y159055D03*
X693700D03*
X690551D03*
X687401D03*
X684252D03*
X681102D03*
X677952D03*
X674803D03*
X671653D03*
X668504D03*
X665354D03*
X662204D03*
X659055D03*
X655905D03*
X652756D03*
X649606D03*
X646456D03*
X643307D03*
X696850Y162204D03*
X693700D03*
X690551D03*
X687401D03*
X684252D03*
X681102D03*
X677952D03*
X674803D03*
X671653D03*
X668504D03*
X665354D03*
X662204D03*
X659055D03*
X655905D03*
X652756D03*
X649606D03*
X646456D03*
X643307D03*
X696850Y165354D03*
X693700D03*
X690551D03*
X687401D03*
X684252D03*
X681102D03*
X677952D03*
X674803D03*
X671653D03*
X668504D03*
X665354D03*
X662204D03*
X659055D03*
X655905D03*
X652756D03*
X649606D03*
X646456D03*
X643307D03*
X696850Y168504D03*
X693700D03*
X690551D03*
X687401D03*
X684252D03*
X681102D03*
X677952D03*
X674803D03*
X671653D03*
X668504D03*
X665354D03*
X662204D03*
X659055D03*
X655905D03*
X652756D03*
X649606D03*
X646456D03*
X643307D03*
X696850Y171653D03*
X693700D03*
X690551D03*
X687401D03*
X684252D03*
X681102D03*
X677952D03*
X674803D03*
X671653D03*
X668504D03*
X665354D03*
X662204D03*
X659055D03*
X655905D03*
X652756D03*
X649606D03*
X646456D03*
X643307D03*
X696850Y174803D03*
X693700D03*
X690551D03*
X687401D03*
X684252D03*
X681102D03*
X677952D03*
X674803D03*
X671653D03*
X668504D03*
X665354D03*
X662204D03*
X659055D03*
X655905D03*
X652756D03*
X649606D03*
X646456D03*
X643307D03*
X696850Y177952D03*
X693700D03*
X690551D03*
X687401D03*
X684252D03*
X681102D03*
X677952D03*
X674803D03*
X671653D03*
X668504D03*
X665354D03*
X662204D03*
X659055D03*
X655905D03*
X652756D03*
X649606D03*
X646456D03*
X643307D03*
X696850Y181102D03*
X693700D03*
X690551D03*
X687401D03*
X684252D03*
X681102D03*
X677952D03*
X674803D03*
X671653D03*
X668504D03*
X665354D03*
X662204D03*
X659055D03*
X655905D03*
X652756D03*
X649606D03*
X646456D03*
X643307D03*
X696850Y184252D03*
X693700D03*
X690551D03*
X687401D03*
X684252D03*
X681102D03*
X677952D03*
X674803D03*
X671653D03*
X668504D03*
X665354D03*
X662204D03*
X659055D03*
X655905D03*
X652756D03*
X649606D03*
X646456D03*
X643307D03*
X696850Y187401D03*
X693700D03*
X690551D03*
X687401D03*
X684252D03*
X681102D03*
X677952D03*
X674803D03*
X671653D03*
X668504D03*
X665354D03*
X662204D03*
X659055D03*
X655905D03*
X652756D03*
X649606D03*
X646456D03*
X643307D03*
X696850Y190551D03*
X693700D03*
X690551D03*
X687401D03*
X684252D03*
X681102D03*
X677952D03*
X674803D03*
X671653D03*
X668504D03*
X665354D03*
X662204D03*
X659055D03*
X655905D03*
X652756D03*
X649606D03*
X646456D03*
X643307D03*
X696850Y193700D03*
X693700D03*
X690551D03*
X687401D03*
X684252D03*
X681102D03*
X677952D03*
X674803D03*
X671653D03*
X668504D03*
X665354D03*
X662204D03*
X659055D03*
X655905D03*
X652756D03*
X649606D03*
X646456D03*
X643307D03*
X696850Y196850D03*
X693700D03*
X690551D03*
X687401D03*
X684252D03*
X681102D03*
X677952D03*
X674803D03*
X671653D03*
X668504D03*
X665354D03*
X662204D03*
X659055D03*
X655905D03*
X652756D03*
X696850Y200000D03*
X693700D03*
X690551D03*
X687401D03*
X684252D03*
X681102D03*
X677952D03*
X674803D03*
X671653D03*
X668504D03*
X665354D03*
X662204D03*
X659055D03*
X655905D03*
X652756D03*
X696850Y203149D03*
X693700D03*
X690551D03*
X687401D03*
X684252D03*
X681102D03*
X677952D03*
X674803D03*
X671653D03*
X668504D03*
X665354D03*
X662204D03*
X659055D03*
X655905D03*
X652756D03*
X725196Y111811D03*
X722047D03*
X718897D03*
X715748D03*
X712598D03*
X709448D03*
X706299D03*
X703149D03*
X700000D03*
X725196Y114960D03*
X722047D03*
X718897D03*
X715748D03*
X712598D03*
X709448D03*
X706299D03*
X703149D03*
X700000D03*
X725196Y118110D03*
X722047D03*
X718897D03*
X715748D03*
X712598D03*
X709448D03*
X706299D03*
X703149D03*
X700000D03*
X734645Y121260D03*
X731496D03*
X728346D03*
X725196D03*
X722047D03*
X718897D03*
X715748D03*
X712598D03*
X709448D03*
X706299D03*
X703149D03*
X700000D03*
X734645Y124409D03*
X731496D03*
X728346D03*
X725196D03*
X722047D03*
X718897D03*
X715748D03*
X712598D03*
X709448D03*
X706299D03*
X703149D03*
X700000D03*
X734645Y127559D03*
X731496D03*
X728346D03*
X725196D03*
X722047D03*
X718897D03*
X715748D03*
X712598D03*
X709448D03*
X706299D03*
X703149D03*
X700000D03*
X734645Y130708D03*
X731496D03*
X728346D03*
X725196D03*
X722047D03*
X718897D03*
X715748D03*
X712598D03*
X709448D03*
X706299D03*
X703149D03*
X700000D03*
X734645Y133858D03*
X731496D03*
X728346D03*
X725196D03*
X722047D03*
X718897D03*
X715748D03*
X712598D03*
X709448D03*
X706299D03*
X703149D03*
X700000D03*
X734645Y137008D03*
X731496D03*
X728346D03*
X725196D03*
X722047D03*
X718897D03*
X715748D03*
X712598D03*
X709448D03*
X706299D03*
X703149D03*
X700000D03*
X734645Y140157D03*
X731496D03*
X728346D03*
X725196D03*
X722047D03*
X718897D03*
X715748D03*
X712598D03*
X709448D03*
X706299D03*
X703149D03*
X700000D03*
X734645Y143307D03*
X731496D03*
X728346D03*
X725196D03*
X722047D03*
X718897D03*
X715748D03*
X712598D03*
X709448D03*
X706299D03*
X703149D03*
X700000D03*
X734645Y146456D03*
X731496D03*
X728346D03*
X725196D03*
X722047D03*
X718897D03*
X715748D03*
X712598D03*
X709448D03*
X706299D03*
X703149D03*
X700000D03*
X734645Y149606D03*
X731496D03*
X728346D03*
X725196D03*
X722047D03*
X718897D03*
X715748D03*
X712598D03*
X709448D03*
X706299D03*
X703149D03*
X700000D03*
X734645Y152756D03*
X731496D03*
X728346D03*
X725196D03*
X722047D03*
X718897D03*
X715748D03*
X712598D03*
X709448D03*
X706299D03*
X703149D03*
X700000D03*
X734645Y155905D03*
X731496D03*
X728346D03*
X725196D03*
X722047D03*
X718897D03*
X715748D03*
X712598D03*
X709448D03*
X706299D03*
X703149D03*
X700000D03*
X734645Y159055D03*
X731496D03*
X728346D03*
X725196D03*
X722047D03*
X718897D03*
X715748D03*
X712598D03*
X709448D03*
X706299D03*
X703149D03*
X700000D03*
X734645Y162204D03*
X731496D03*
X728346D03*
X725196D03*
X722047D03*
X718897D03*
X715748D03*
X712598D03*
X709448D03*
X706299D03*
X703149D03*
X700000D03*
X734645Y165354D03*
X731496D03*
X728346D03*
X725196D03*
X722047D03*
X718897D03*
X715748D03*
X712598D03*
X709448D03*
X706299D03*
X703149D03*
X700000D03*
X734645Y168504D03*
X731496D03*
X728346D03*
X725196D03*
X722047D03*
X718897D03*
X715748D03*
X712598D03*
X709448D03*
X706299D03*
X703149D03*
X700000D03*
X734645Y171653D03*
X731496D03*
X728346D03*
X725196D03*
X722047D03*
X718897D03*
X715748D03*
X712598D03*
X709448D03*
X706299D03*
X703149D03*
X700000D03*
X734645Y174803D03*
X731496D03*
X728346D03*
X725196D03*
X722047D03*
X718897D03*
X715748D03*
X712598D03*
X709448D03*
X706299D03*
X703149D03*
X700000D03*
X734645Y177952D03*
X731496D03*
X728346D03*
X725196D03*
X722047D03*
X718897D03*
X715748D03*
X712598D03*
X709448D03*
X706299D03*
X703149D03*
X700000D03*
X734645Y181102D03*
X731496D03*
X728346D03*
X725196D03*
X722047D03*
X718897D03*
X715748D03*
X712598D03*
X709448D03*
X706299D03*
X703149D03*
X700000D03*
X734645Y184252D03*
X731496D03*
X728346D03*
X725196D03*
X722047D03*
X718897D03*
X715748D03*
X712598D03*
X709448D03*
X706299D03*
X703149D03*
X700000D03*
X734645Y187401D03*
X731496D03*
X728346D03*
X725196D03*
X722047D03*
X718897D03*
X715748D03*
X712598D03*
X709448D03*
X706299D03*
X703149D03*
X700000D03*
X734645Y190551D03*
X731496D03*
X728346D03*
X725196D03*
X722047D03*
X718897D03*
X715748D03*
X712598D03*
X709448D03*
X706299D03*
X703149D03*
X700000D03*
X734645Y193700D03*
X731496D03*
X728346D03*
X725196D03*
X722047D03*
X718897D03*
X715748D03*
X712598D03*
X709448D03*
X706299D03*
X703149D03*
X700000D03*
X725196Y196850D03*
X722047D03*
X718897D03*
X715748D03*
X712598D03*
X709448D03*
X706299D03*
X703149D03*
X700000D03*
X725196Y200000D03*
X722047D03*
X718897D03*
X715748D03*
X712598D03*
X709448D03*
X706299D03*
X703149D03*
X700000D03*
X725196Y203149D03*
X722047D03*
X718897D03*
X715748D03*
X712598D03*
X709448D03*
X706299D03*
X703149D03*
X700000D03*
X775486Y287316D03*
G54D37*
X59800Y183100D03*
X82600Y222700D03*
X176500Y169800D03*
X178500Y193200D03*
X297000Y159200D03*
X296500Y200300D03*
Y242350D03*
X569070Y460430D03*
X581000Y392700D03*
X695700Y390250D03*
X647623Y378489D03*
X642907D03*
X715800Y381800D03*
X736400Y456600D03*
G54D29*
X66403Y133450D03*
X59997D03*
G54D83*
X289500Y136500D03*
Y147500D03*
Y167500D03*
Y156500D03*
Y239500D03*
Y209000D03*
Y198000D03*
Y178500D03*
Y189500D03*
Y220000D03*
Y231000D03*
Y250500D03*
X573500Y401500D03*
Y390500D03*
G54D65*
X185789Y175500D03*
Y180500D03*
X208011Y175500D03*
Y190500D03*
Y185500D03*
Y180500D03*
G54D38*
X61790Y199650D03*
X48010D03*
Y219750D03*
X61790D03*
G54D47*
X75400Y318200D03*
X50300Y387500D03*
X77700Y291700D03*
X99450Y452650D03*
X225800Y95000D03*
X245300D03*
X242600Y279700D03*
X235400Y316900D03*
X253775Y316967D03*
X218000Y317000D03*
X273165Y317151D03*
X294900Y328300D03*
X360100Y334000D03*
X629800Y166500D03*
X632800Y299091D03*
Y288745D03*
Y337500D03*
Y327654D03*
X626370Y369320D03*
X627070Y389940D03*
X590150Y482900D03*
X599300Y434500D03*
X693535Y441196D03*
X717700Y489400D03*
G54D56*
X116063Y39075D03*
G54D92*
X389764Y460630D03*
X437008D03*
G54D74*
X261102Y75310D03*
Y73735D03*
Y72160D03*
Y70585D03*
Y69010D03*
Y67435D03*
Y65865D03*
Y64290D03*
Y62715D03*
Y61140D03*
Y59565D03*
Y57990D03*
X283302D03*
Y59565D03*
Y61140D03*
Y62715D03*
Y64290D03*
Y65865D03*
Y67435D03*
Y69010D03*
Y70585D03*
Y72160D03*
Y73735D03*
Y75310D03*
X322650Y278826D03*
Y277251D03*
Y275676D03*
Y274101D03*
Y272526D03*
Y270951D03*
Y269381D03*
Y267806D03*
Y266231D03*
Y264656D03*
Y263081D03*
Y261506D03*
X344850D03*
Y263081D03*
Y264656D03*
Y266231D03*
Y267806D03*
Y269381D03*
Y270951D03*
Y272526D03*
Y274101D03*
Y275676D03*
Y277251D03*
Y278826D03*
G54D75*
X235500Y147500D03*
X260300D03*
X234750Y238600D03*
X259550D03*
X234700Y213500D03*
X259500D03*
X211600Y456500D03*
X236400D03*
X520600Y445500D03*
X545400D03*
X741293Y355942D03*
X716493D03*
X741293Y330892D03*
X716493D03*
G54D48*
X71165Y357207D03*
X73725D03*
X76285D03*
Y344407D03*
X73725D03*
X71165D03*
X28465Y357007D03*
X31025D03*
X33585D03*
X36145D03*
Y344207D03*
X33585D03*
X31025D03*
X28465D03*
X49465Y356807D03*
X52025D03*
X54585D03*
X57145D03*
Y344007D03*
X54585D03*
X52025D03*
X49465D03*
X78845Y357207D03*
Y344407D03*
X92260Y357000D03*
X94820D03*
X97380D03*
X99940D03*
Y344200D03*
X97380D03*
X94820D03*
X92260D03*
X234872Y298705D03*
X232312D03*
X229752D03*
X227192D03*
X253215Y298667D03*
X250655D03*
X248095D03*
X245535D03*
X216640Y298700D03*
X214080D03*
X211520D03*
X208960D03*
X227192Y311505D03*
X229752D03*
X232312D03*
X234872D03*
X245535Y311467D03*
X248095D03*
X250655D03*
X253215D03*
X208960Y311500D03*
X211520D03*
X214080D03*
X216640D03*
X272637Y298956D03*
X270077D03*
X267517D03*
X264957D03*
Y311756D03*
X267517D03*
X270077D03*
X272637D03*
G54D39*
X59821Y199950D03*
X57853D03*
X55884D03*
X53916D03*
X51947D03*
X49979D03*
Y219450D03*
X51947D03*
X53916D03*
X55884D03*
X57853D03*
X59821D03*
G54D66*
X196900Y183000D03*
G54D84*
X272268Y395524D03*
G54D57*
X88600Y199400D03*
Y209400D03*
Y204400D03*
X176100Y104500D03*
X194457Y153196D03*
X261800Y431000D03*
X280800Y141000D03*
X280300Y163000D03*
X280800Y204500D03*
X280300Y183000D03*
X280800Y224500D03*
X280300Y246000D03*
X324259Y301695D03*
X576100Y489700D03*
X694900Y306300D03*
X649260Y390820D03*
X690300Y377500D03*
G54D93*
X446850Y202756D03*
X442913D03*
X438976D03*
X435039D03*
X431102D03*
X427165D03*
X423228D03*
X419291D03*
X415354D03*
X411417D03*
X407480D03*
X403543D03*
X446850Y206693D03*
X442913D03*
X438976D03*
X435039D03*
X431102D03*
X427165D03*
X423228D03*
X419291D03*
X415354D03*
X411417D03*
X407480D03*
X403543D03*
X446850Y210630D03*
X442913D03*
X438976D03*
X435039D03*
X431102D03*
X427165D03*
X423228D03*
X419291D03*
X415354D03*
X411417D03*
X407480D03*
X403543D03*
X446850Y214567D03*
X442913D03*
X438976D03*
X435039D03*
X431102D03*
X427165D03*
X423228D03*
X419291D03*
X415354D03*
X411417D03*
X407480D03*
X403543D03*
X399606D03*
X395669D03*
X391732D03*
X446850Y218504D03*
X442913D03*
X438976D03*
X435039D03*
X431102D03*
X427165D03*
X423228D03*
X419291D03*
X415354D03*
X411417D03*
X407480D03*
X403543D03*
X399606D03*
X395669D03*
X391732D03*
X446850Y222441D03*
X442913D03*
X438976D03*
X435039D03*
X431102D03*
X427165D03*
X423228D03*
X419291D03*
X415354D03*
X411417D03*
X407480D03*
X403543D03*
X399606D03*
X395669D03*
X391732D03*
X446850Y226378D03*
X442913D03*
X438976D03*
X435039D03*
X431102D03*
X427165D03*
X423228D03*
X419291D03*
X415354D03*
X411417D03*
X407480D03*
X403543D03*
X399606D03*
X395669D03*
X391732D03*
X446850Y230315D03*
X442913D03*
X438976D03*
X435039D03*
X431102D03*
X427165D03*
X423228D03*
X419291D03*
X415354D03*
X411417D03*
X407480D03*
X403543D03*
X399606D03*
X395669D03*
X391732D03*
X446850Y234252D03*
X442913D03*
X438976D03*
X435039D03*
X431102D03*
X427165D03*
X423228D03*
X419291D03*
X415354D03*
X411417D03*
X407480D03*
X403543D03*
X399606D03*
X395669D03*
X391732D03*
X446850Y238189D03*
X442913D03*
X438976D03*
X435039D03*
X431102D03*
X427165D03*
X423228D03*
X419291D03*
X415354D03*
X411417D03*
X407480D03*
X403543D03*
X399606D03*
X395669D03*
X391732D03*
X446850Y242126D03*
X442913D03*
X438976D03*
X435039D03*
X431102D03*
X427165D03*
X423228D03*
X419291D03*
X415354D03*
X411417D03*
X407480D03*
X403543D03*
X399606D03*
X395669D03*
X391732D03*
X446850Y246063D03*
X442913D03*
X438976D03*
X435039D03*
X431102D03*
X427165D03*
X423228D03*
X419291D03*
X415354D03*
X411417D03*
X407480D03*
X403543D03*
X399606D03*
X395669D03*
X391732D03*
X446850Y250000D03*
X442913D03*
X438976D03*
X435039D03*
X431102D03*
X427165D03*
X423228D03*
X419291D03*
X415354D03*
X411417D03*
X407480D03*
X403543D03*
X399606D03*
X395669D03*
X391732D03*
X446850Y253937D03*
X442913D03*
X438976D03*
X435039D03*
X431102D03*
X427165D03*
X423228D03*
X419291D03*
X415354D03*
X411417D03*
X407480D03*
X403543D03*
X399606D03*
X395669D03*
X391732D03*
X446850Y257874D03*
X442913D03*
X438976D03*
X435039D03*
X431102D03*
X427165D03*
X423228D03*
X419291D03*
X415354D03*
X411417D03*
X407480D03*
X403543D03*
X399606D03*
X395669D03*
X391732D03*
X446850Y261811D03*
X442913D03*
X438976D03*
X435039D03*
X431102D03*
X427165D03*
X423228D03*
X419291D03*
X415354D03*
X411417D03*
X407480D03*
X403543D03*
X399606D03*
X395669D03*
X391732D03*
X446850Y265749D03*
X442913D03*
X438976D03*
X435039D03*
X431102D03*
X427165D03*
X423228D03*
X419291D03*
X415354D03*
X411417D03*
X407480D03*
X403543D03*
X399606D03*
X395669D03*
X391732D03*
X446850Y269686D03*
X442913D03*
X438976D03*
X435039D03*
X431102D03*
X427165D03*
X423228D03*
X419291D03*
X415354D03*
X411417D03*
X407480D03*
X403543D03*
X399606D03*
X395669D03*
X391732D03*
X446850Y273623D03*
X442913D03*
X438976D03*
X435039D03*
X431102D03*
X427165D03*
X423228D03*
X419291D03*
X415354D03*
X411417D03*
X407480D03*
X403543D03*
X399606D03*
X395669D03*
X391732D03*
X446850Y277560D03*
X442913D03*
X438976D03*
X435039D03*
X431102D03*
X427165D03*
X423228D03*
X419291D03*
X415354D03*
X411417D03*
X407480D03*
X403543D03*
X399606D03*
X395669D03*
X391732D03*
X446850Y281497D03*
X442913D03*
X438976D03*
X435039D03*
X431102D03*
X427165D03*
X423228D03*
X419291D03*
X415354D03*
X411417D03*
X407480D03*
X403543D03*
X399606D03*
X395669D03*
X391732D03*
X446850Y285434D03*
X442913D03*
X438976D03*
X435039D03*
X431102D03*
X427165D03*
X423228D03*
X419291D03*
X415354D03*
X411417D03*
X407480D03*
X403543D03*
X399606D03*
X395669D03*
X391732D03*
X446850Y289371D03*
X442913D03*
X438976D03*
X435039D03*
X431102D03*
X427165D03*
X423228D03*
X419291D03*
X415354D03*
X411417D03*
X407480D03*
X403543D03*
X399606D03*
X395669D03*
X391732D03*
X446850Y293308D03*
X442913D03*
X438976D03*
X435039D03*
X431102D03*
X427165D03*
X423228D03*
X419291D03*
X415354D03*
X411417D03*
X407480D03*
X403543D03*
X399606D03*
X395669D03*
X391732D03*
X446850Y297245D03*
X442913D03*
X438976D03*
X435039D03*
X431102D03*
X427165D03*
X423228D03*
X419291D03*
X415354D03*
X411417D03*
X407480D03*
X403543D03*
X399606D03*
X395669D03*
X391732D03*
X446850Y301182D03*
X442913D03*
X438976D03*
X435039D03*
X431102D03*
X427165D03*
X423228D03*
X419291D03*
X415354D03*
X411417D03*
X407480D03*
X403543D03*
X399606D03*
X395669D03*
X391732D03*
X446850Y305119D03*
X442913D03*
X438976D03*
X435039D03*
X431102D03*
X427165D03*
X423228D03*
X419291D03*
X415354D03*
X411417D03*
X407480D03*
X403543D03*
X399606D03*
X395669D03*
X391732D03*
X446850Y309056D03*
X442913D03*
X438976D03*
X435039D03*
X431102D03*
X427165D03*
X423228D03*
X419291D03*
X415354D03*
X411417D03*
X407480D03*
X403543D03*
X399606D03*
X395669D03*
X391732D03*
X446850Y312993D03*
X442913D03*
X438976D03*
X435039D03*
X431102D03*
X427165D03*
X423228D03*
X419291D03*
X415354D03*
X411417D03*
X407480D03*
X403543D03*
X399606D03*
X395669D03*
X391732D03*
X446850Y316930D03*
X442913D03*
X438976D03*
X435039D03*
X431102D03*
X427165D03*
X423228D03*
X419291D03*
X415354D03*
X411417D03*
X407480D03*
X403543D03*
X446850Y320867D03*
X442913D03*
X438976D03*
X435039D03*
X431102D03*
X427165D03*
X423228D03*
X419291D03*
X415354D03*
X411417D03*
X407480D03*
X403543D03*
X446850Y324804D03*
X442913D03*
X438976D03*
X435039D03*
X431102D03*
X427165D03*
X423228D03*
X419291D03*
X415354D03*
X411417D03*
X407480D03*
X403543D03*
X501969Y202756D03*
X498032D03*
X494095D03*
X490158D03*
X486221D03*
X482284D03*
X478347D03*
X474410D03*
X470473D03*
X466536D03*
X462599D03*
X458662D03*
X454725D03*
X450787D03*
X501969Y206693D03*
X498032D03*
X494095D03*
X490158D03*
X486221D03*
X482284D03*
X478347D03*
X474410D03*
X470473D03*
X466536D03*
X462599D03*
X458662D03*
X454725D03*
X450787D03*
X501969Y210630D03*
X498032D03*
X494095D03*
X490158D03*
X486221D03*
X482284D03*
X478347D03*
X474410D03*
X470473D03*
X466536D03*
X462599D03*
X458662D03*
X454725D03*
X450787D03*
X509843Y214567D03*
X505906D03*
X501969D03*
X498032D03*
X494095D03*
X490158D03*
X486221D03*
X482284D03*
X478347D03*
X474410D03*
X470473D03*
X466536D03*
X462599D03*
X458662D03*
X454725D03*
X450787D03*
X509843Y218504D03*
X505906D03*
X501969D03*
X498032D03*
X494095D03*
X490158D03*
X486221D03*
X482284D03*
X478347D03*
X474410D03*
X470473D03*
X466536D03*
X462599D03*
X458662D03*
X454725D03*
X450787D03*
X509843Y222441D03*
X505906D03*
X501969D03*
X498032D03*
X494095D03*
X490158D03*
X486221D03*
X482284D03*
X478347D03*
X474410D03*
X470473D03*
X466536D03*
X462599D03*
X458662D03*
X454725D03*
X450787D03*
X509843Y226378D03*
X505906D03*
X501969D03*
X498032D03*
X494095D03*
X490158D03*
X486221D03*
X482284D03*
X478347D03*
X474410D03*
X470473D03*
X466536D03*
X462599D03*
X458662D03*
X454725D03*
X450787D03*
X509843Y230315D03*
X505906D03*
X501969D03*
X498032D03*
X494095D03*
X490158D03*
X486221D03*
X482284D03*
X478347D03*
X474410D03*
X470473D03*
X466536D03*
X462599D03*
X458662D03*
X454725D03*
X450787D03*
X509843Y234252D03*
X505906D03*
X501969D03*
X498032D03*
X494095D03*
X490158D03*
X486221D03*
X482284D03*
X478347D03*
X474410D03*
X470473D03*
X466536D03*
X462599D03*
X458662D03*
X454725D03*
X450787D03*
X509843Y238189D03*
X505906D03*
X501969D03*
X498032D03*
X494095D03*
X490158D03*
X486221D03*
X482284D03*
X478347D03*
X474410D03*
X470473D03*
X466536D03*
X462599D03*
X458662D03*
X454725D03*
X450787D03*
X509843Y242126D03*
X505906D03*
X501969D03*
X498032D03*
X494095D03*
X490158D03*
X486221D03*
X482284D03*
X478347D03*
X474410D03*
X470473D03*
X466536D03*
X462599D03*
X458662D03*
X454725D03*
X450787D03*
X509843Y246063D03*
X505906D03*
X501969D03*
X498032D03*
X494095D03*
X490158D03*
X486221D03*
X482284D03*
X478347D03*
X474410D03*
X470473D03*
X466536D03*
X462599D03*
X458662D03*
X454725D03*
X450787D03*
X509843Y250000D03*
X505906D03*
X501969D03*
X498032D03*
X494095D03*
X490158D03*
X486221D03*
X482284D03*
X478347D03*
X474410D03*
X470473D03*
X466536D03*
X462599D03*
X458662D03*
X454725D03*
X450787D03*
X509843Y253937D03*
X505906D03*
X501969D03*
X498032D03*
X494095D03*
X490158D03*
X486221D03*
X482284D03*
X478347D03*
X474410D03*
X470473D03*
X466536D03*
X462599D03*
X458662D03*
X454725D03*
X450787D03*
X509843Y257874D03*
X505906D03*
X501969D03*
X498032D03*
X494095D03*
X490158D03*
X486221D03*
X482284D03*
X478347D03*
X474410D03*
X470473D03*
X466536D03*
X462599D03*
X458662D03*
X454725D03*
X450787D03*
X509843Y261811D03*
X505906D03*
X501969D03*
X498032D03*
X494095D03*
X490158D03*
X486221D03*
X482284D03*
X478347D03*
X474410D03*
X470473D03*
X466536D03*
X462599D03*
X458662D03*
X454725D03*
X450787D03*
X509843Y265749D03*
X505906D03*
X501969D03*
X498032D03*
X494095D03*
X490158D03*
X486221D03*
X482284D03*
X478347D03*
X474410D03*
X470473D03*
X466536D03*
X462599D03*
X458662D03*
X454725D03*
X450787D03*
X509843Y269686D03*
X505906D03*
X501969D03*
X498032D03*
X494095D03*
X490158D03*
X486221D03*
X482284D03*
X478347D03*
X474410D03*
X470473D03*
X466536D03*
X462599D03*
X458662D03*
X454725D03*
X450787D03*
X509843Y273623D03*
X505906D03*
X501969D03*
X498032D03*
X494095D03*
X490158D03*
X486221D03*
X482284D03*
X478347D03*
X474410D03*
X470473D03*
X466536D03*
X462599D03*
X458662D03*
X454725D03*
X450787D03*
X509843Y277560D03*
X505906D03*
X501969D03*
X498032D03*
X494095D03*
X490158D03*
X486221D03*
X482284D03*
X478347D03*
X474410D03*
X470473D03*
X466536D03*
X462599D03*
X458662D03*
X454725D03*
X450787D03*
X509843Y281497D03*
X505906D03*
X501969D03*
X498032D03*
X494095D03*
X490158D03*
X486221D03*
X482284D03*
X478347D03*
X474410D03*
X470473D03*
X466536D03*
X462599D03*
X458662D03*
X454725D03*
X450787D03*
X509843Y285434D03*
X505906D03*
X501969D03*
X498032D03*
X494095D03*
X490158D03*
X486221D03*
X482284D03*
X478347D03*
X474410D03*
X470473D03*
X466536D03*
X462599D03*
X458662D03*
X454725D03*
X450787D03*
X509843Y289371D03*
X505906D03*
X501969D03*
X498032D03*
X494095D03*
X490158D03*
X486221D03*
X482284D03*
X478347D03*
X474410D03*
X470473D03*
X466536D03*
X462599D03*
X458662D03*
X454725D03*
X450787D03*
X509843Y293308D03*
X505906D03*
X501969D03*
X498032D03*
X494095D03*
X490158D03*
X486221D03*
X482284D03*
X478347D03*
X474410D03*
X470473D03*
X466536D03*
X462599D03*
X458662D03*
X454725D03*
X450787D03*
X509843Y297245D03*
X505906D03*
X501969D03*
X498032D03*
X494095D03*
X490158D03*
X486221D03*
X482284D03*
X478347D03*
X474410D03*
X470473D03*
X466536D03*
X462599D03*
X458662D03*
X454725D03*
X450787D03*
X509843Y301182D03*
X505906D03*
X501969D03*
X498032D03*
X494095D03*
X490158D03*
X486221D03*
X482284D03*
X478347D03*
X474410D03*
X470473D03*
X466536D03*
X462599D03*
X458662D03*
X454725D03*
X450787D03*
X509843Y305119D03*
X505906D03*
X501969D03*
X498032D03*
X494095D03*
X490158D03*
X486221D03*
X482284D03*
X478347D03*
X474410D03*
X470473D03*
X466536D03*
X462599D03*
X458662D03*
X454725D03*
X450787D03*
X509843Y309056D03*
X505906D03*
X501969D03*
X498032D03*
X494095D03*
X490158D03*
X486221D03*
X482284D03*
X478347D03*
X474410D03*
X470473D03*
X466536D03*
X462599D03*
X458662D03*
X454725D03*
X450787D03*
X509843Y312993D03*
X505906D03*
X501969D03*
X498032D03*
X494095D03*
X490158D03*
X486221D03*
X482284D03*
X478347D03*
X474410D03*
X470473D03*
X466536D03*
X462599D03*
X458662D03*
X454725D03*
X450787D03*
X501969Y316930D03*
X498032D03*
X494095D03*
X490158D03*
X486221D03*
X482284D03*
X478347D03*
X474410D03*
X470473D03*
X466536D03*
X462599D03*
X458662D03*
X454725D03*
X450787D03*
X501969Y320867D03*
X498032D03*
X494095D03*
X490158D03*
X486221D03*
X482284D03*
X478347D03*
X474410D03*
X470473D03*
X466536D03*
X462599D03*
X458662D03*
X454725D03*
X450787D03*
X501969Y324804D03*
X498032D03*
X494095D03*
X490158D03*
X486221D03*
X482284D03*
X478347D03*
X474410D03*
X470473D03*
X466536D03*
X462599D03*
X458662D03*
X454725D03*
X450787D03*
X513780Y214567D03*
Y218504D03*
Y222441D03*
Y226378D03*
Y230315D03*
Y234252D03*
Y238189D03*
Y242126D03*
Y246063D03*
Y250000D03*
Y253937D03*
Y257874D03*
Y261811D03*
Y265749D03*
Y269686D03*
Y273623D03*
Y277560D03*
Y281497D03*
Y285434D03*
Y289371D03*
Y293308D03*
Y297245D03*
Y301182D03*
Y305119D03*
Y309056D03*
Y312993D03*
G54D67*
X193264Y138648D03*
X605570Y475480D03*
G54D85*
X269768Y395524D03*
G54D49*
X77257Y392835D03*
Y395395D03*
Y397955D03*
X70757D03*
Y392835D03*
X36850Y398560D03*
Y396000D03*
Y393440D03*
X43350D03*
Y398560D03*
G54D58*
X83000Y199400D03*
Y209400D03*
Y204400D03*
X170500Y104500D03*
X188857Y153196D03*
X256200Y431000D03*
X275200Y141000D03*
X274700Y163000D03*
X275200Y204500D03*
X274700Y183000D03*
X275200Y224500D03*
X274700Y246000D03*
X318659Y301695D03*
X570500Y489700D03*
X689300Y306300D03*
X643660Y390820D03*
X684700Y377500D03*
G54D94*
X401575Y410039D03*
X410433D03*
X419292D03*
X404528Y412795D03*
X413386D03*
X422244D03*
X401575Y425000D03*
X410433D03*
X419292D03*
X407480Y422244D03*
X416339D03*
X425197D03*
X407480Y407284D03*
X416339D03*
X425197D03*
X404528Y427756D03*
X413386D03*
X422244D03*
X401575Y439961D03*
X410433D03*
X419292D03*
X404528Y442717D03*
X413386D03*
X422244D03*
X401575Y454921D03*
X410433D03*
X419292D03*
X404528Y457677D03*
X413386D03*
X422244D03*
X407480Y437205D03*
X416339D03*
X425197D03*
X407480Y452165D03*
X416339D03*
X425197D03*
G54D76*
X254124Y180500D03*
X221876D03*
G54D77*
X229700Y384200D03*
X254920Y376270D03*
G54D86*
X295275Y531496D03*
X531495D03*
G54D59*
X125850Y183400D03*
X141350D03*
X644681Y314583D03*
X660181D03*
G54D95*
X496499Y175070D03*
X494199D03*
X506245Y175012D03*
X503945D03*
X496499Y177270D03*
X494199D03*
X506245Y177212D03*
X503945D03*
X516370Y174954D03*
X514070D03*
X526495Y174896D03*
X524195D03*
X516370Y177154D03*
X514070D03*
X526495Y177096D03*
X524195D03*
G54D68*
X193264Y136148D03*
X605570Y472980D03*
G54D69*
X171694Y134453D03*
Y132484D03*
Y130516D03*
Y128547D03*
X183906D03*
Y130516D03*
Y132484D03*
Y134453D03*
G54D96*
X571249Y127362D03*
X573401Y127820D03*
X570771Y129612D03*
X572923Y130070D03*
X584086Y174012D03*
X586238Y174470D03*
X579993Y158187D03*
X582145Y158645D03*
X579515Y160436D03*
X581667Y160894D03*
X589314Y149359D03*
X591466Y149817D03*
X588836Y151608D03*
X590988Y152066D03*
X582353Y138181D03*
X584505Y138639D03*
X581875Y140430D03*
X584027Y140888D03*
X583321Y214047D03*
X585473Y214505D03*
X582842Y216296D03*
X584994Y216754D03*
X579391Y198464D03*
X581543Y198922D03*
X578913Y200713D03*
X581065Y201171D03*
X575189Y182722D03*
X577341Y183180D03*
X574711Y184971D03*
X576863Y185429D03*
X583608Y176262D03*
X585760Y176720D03*
G54D87*
X388189Y48426D03*
X374016D03*
X359843D03*
X345670D03*
X388189Y34252D03*
X374016D03*
X359843D03*
X345670D03*
X388189Y20079D03*
X374016D03*
X359843D03*
X345670D03*
X388189Y44095D03*
X374016D03*
X359843D03*
X345670D03*
X388189Y38583D03*
X374016D03*
X359843D03*
X345670D03*
X388189Y29922D03*
X374016D03*
X359843D03*
X345670D03*
X388189Y24410D03*
X374016D03*
X359843D03*
X345670D03*
X388189Y15748D03*
X374016D03*
X359843D03*
X345670D03*
X388189Y10237D03*
X374016D03*
X359843D03*
X345670D03*
X388189Y5906D03*
X374016D03*
X359843D03*
X345670D03*
X381103Y38977D03*
X366929D03*
X352756D03*
X338583D03*
X381103Y24804D03*
X366929D03*
X352756D03*
X338583D03*
X381103Y53150D03*
X366929D03*
X352756D03*
X338583D03*
X381103Y48819D03*
X366929D03*
X352756D03*
X338583D03*
X381103Y43307D03*
X366929D03*
X352756D03*
X338583D03*
X381103Y34646D03*
X366929D03*
X352756D03*
X338583D03*
X381103Y29134D03*
X366929D03*
X352756D03*
X338583D03*
X381103Y20473D03*
X366929D03*
X352756D03*
X338583D03*
X381103Y14961D03*
X366929D03*
X352756D03*
X338583D03*
X444882Y48426D03*
X430709D03*
X416536D03*
X402363D03*
X444882Y34252D03*
X430709D03*
X416536D03*
X402363D03*
X444882Y20079D03*
X430709D03*
X416536D03*
X402363D03*
X444882Y44095D03*
X430709D03*
X416536D03*
X402363D03*
X444882Y38583D03*
X430709D03*
X416536D03*
X402363D03*
X444882Y29922D03*
X430709D03*
X416536D03*
X402363D03*
X444882Y24410D03*
X430709D03*
X416536D03*
X402363D03*
X444882Y15748D03*
X430709D03*
X416536D03*
X402363D03*
X444882Y10237D03*
X430709D03*
X416536D03*
X402363D03*
X444882Y5906D03*
X430709D03*
X416536D03*
X402363D03*
X437796Y38977D03*
X423622D03*
X409449D03*
X395276D03*
X437796Y24804D03*
X423622D03*
X409449D03*
X395276D03*
X437796Y53150D03*
X423622D03*
X409449D03*
X395276D03*
X437796Y48819D03*
X423622D03*
X409449D03*
X395276D03*
X437796Y43307D03*
X423622D03*
X409449D03*
X395276D03*
X437796Y34646D03*
X423622D03*
X409449D03*
X395276D03*
X437796Y29134D03*
X423622D03*
X409449D03*
X395276D03*
X437796Y20473D03*
X423622D03*
X409449D03*
X395276D03*
X437796Y14961D03*
X423622D03*
X409449D03*
X395276D03*
X501575Y48426D03*
X487402D03*
X473229D03*
X459055D03*
X501575Y34252D03*
X487402D03*
X473229D03*
X459055D03*
X501575Y20079D03*
X487402D03*
X473229D03*
X459055D03*
X501575Y44095D03*
X487402D03*
X473229D03*
X459055D03*
X501575Y38583D03*
X487402D03*
X473229D03*
X459055D03*
X501575Y29922D03*
X487402D03*
X473229D03*
X459055D03*
X501575Y24410D03*
X487402D03*
X473229D03*
X459055D03*
X501575Y15748D03*
X487402D03*
X473229D03*
X459055D03*
X501575Y10237D03*
X487402D03*
X473229D03*
X459055D03*
X501575Y5906D03*
X487402D03*
X473229D03*
X459055D03*
X508662Y38977D03*
X494489D03*
X480315D03*
X466142D03*
X451969D03*
X508662Y24804D03*
X494489D03*
X480315D03*
X466142D03*
X451969D03*
X508662Y53150D03*
X494489D03*
X480315D03*
X466142D03*
X451969D03*
X508662Y48819D03*
X494489D03*
X480315D03*
X466142D03*
X451969D03*
X508662Y43307D03*
X494489D03*
X480315D03*
X466142D03*
X451969D03*
X508662Y34646D03*
X494489D03*
X480315D03*
X466142D03*
X451969D03*
X508662Y29134D03*
X494489D03*
X480315D03*
X466142D03*
X451969D03*
X508662Y20473D03*
X494489D03*
X480315D03*
X466142D03*
X451969D03*
X508662Y14961D03*
X494489D03*
X480315D03*
X466142D03*
X451969D03*
X572441Y48426D03*
X558268D03*
X544095D03*
X529922D03*
X515748D03*
X572441Y34252D03*
X558268D03*
X544095D03*
X529922D03*
X515748D03*
X572441Y20079D03*
X558268D03*
X544095D03*
X529922D03*
X515748D03*
X572441Y44095D03*
X558268D03*
X544095D03*
X529922D03*
X515748D03*
X572441Y38583D03*
X558268D03*
X544095D03*
X529922D03*
X515748D03*
X572441Y29922D03*
X558268D03*
X544095D03*
X529922D03*
X515748D03*
X572441Y24410D03*
X558268D03*
X544095D03*
X529922D03*
X515748D03*
X572441Y15748D03*
X558268D03*
X544095D03*
X529922D03*
X515748D03*
X572441Y10237D03*
X558268D03*
X544095D03*
X529922D03*
X515748D03*
X572441Y5906D03*
X558268D03*
X544095D03*
X529922D03*
X515748D03*
X565355Y38977D03*
X551181D03*
X537008D03*
X522835D03*
X565355Y24804D03*
X551181D03*
X537008D03*
X522835D03*
X565355Y53150D03*
X551181D03*
X537008D03*
X522835D03*
X565355Y48819D03*
X551181D03*
X537008D03*
X522835D03*
X565355Y43307D03*
X551181D03*
X537008D03*
X522835D03*
X565355Y34646D03*
X551181D03*
X537008D03*
X522835D03*
X565355Y29134D03*
X551181D03*
X537008D03*
X522835D03*
X565355Y20473D03*
X551181D03*
X537008D03*
X522835D03*
X565355Y14961D03*
X551181D03*
X537008D03*
X522835D03*
X586614Y48426D03*
Y34252D03*
Y20079D03*
Y44095D03*
Y38583D03*
Y29922D03*
Y24410D03*
Y15748D03*
Y10237D03*
Y5906D03*
X579528Y38977D03*
Y24804D03*
Y53150D03*
Y48819D03*
Y43307D03*
Y34646D03*
Y29134D03*
Y20473D03*
Y14961D03*
X758267Y48426D03*
X744094D03*
X729921D03*
X715748D03*
X758267Y44095D03*
X744094D03*
X729921D03*
X715748D03*
X758267Y38583D03*
X744094D03*
X729921D03*
X715748D03*
X758267Y34252D03*
X744094D03*
X729921D03*
X715748D03*
X758267Y29922D03*
X744094D03*
X729921D03*
X715748D03*
X758267Y24410D03*
X744094D03*
X729921D03*
X715748D03*
X758267Y20079D03*
X744094D03*
X729921D03*
X715748D03*
X758267Y15748D03*
X744094D03*
X729921D03*
X715748D03*
X758267Y10237D03*
X744094D03*
X729921D03*
X715748D03*
X758267Y5906D03*
X744094D03*
X729921D03*
X715748D03*
X751181Y53150D03*
X737007D03*
X722834D03*
X708661D03*
X751181Y48819D03*
X737007D03*
X722834D03*
X708661D03*
X751181Y43307D03*
X737007D03*
X722834D03*
X708661D03*
X751181Y38977D03*
X737007D03*
X722834D03*
X708661D03*
X751181Y34646D03*
X737007D03*
X722834D03*
X708661D03*
X751181Y29134D03*
X737007D03*
X722834D03*
X708661D03*
X751181Y24804D03*
X737007D03*
X722834D03*
X708661D03*
X751181Y20473D03*
X737007D03*
X722834D03*
X708661D03*
X751181Y14961D03*
X737007D03*
X722834D03*
X708661D03*
G54D78*
X235300Y384200D03*
X260520Y376270D03*
G54D88*
X374015Y156220D03*
X531496Y371299D03*
X596456Y116142D03*
X781496Y198818D03*
G54D97*
X564065Y229550D03*
X561865D03*
X564065Y227250D03*
X561865D03*
X562430Y235988D03*
X560230D03*
X562430Y238288D03*
X560230D03*
X561540Y245859D03*
X559340D03*
X561540Y243559D03*
X559340D03*
X563219Y253446D03*
X561019D03*
X563219Y251146D03*
X561019D03*
G54D79*
X251870Y395670D03*
G54D89*
X341757Y215563D03*
X335701D03*
X341757Y219461D03*
X335701D03*
G54D98*
X535313Y298880D03*
X537513D03*
X535313Y296680D03*
X537513D03*
X535048Y306421D03*
X537248D03*
X535048Y304221D03*
X537248D03*
X535228Y311698D03*
X537428D03*
X535300Y319400D03*
X537500D03*
X535228Y313898D03*
X537428D03*
X535300Y317200D03*
X537500D03*
G54D99*
X560513Y441531D03*
X582399D03*
M02*
